G04 ================== begin FILE IDENTIFICATION RECORD ==================*
G04 Layout Name:  12433-1M.brd*
G04 Film Name:    L1*
G04 File Format:  Gerber RS274X*
G04 File Origin:  Cadence Allegro 16.2-S037*
G04 Origin Date:  Fri Dec 07 18:55:11 2012*
G04 *
G04 Layer:  VIA CLASS/TOP*
G04 Layer:  PIN/TOP*
G04 Layer:  ETCH/TOP*
G04 Layer:  DRAWING FORMAT/LAYER_PCB_STORY*
G04 Layer:  DRAWING FORMAT/LAYER_L1*
G04 *
G04 Offset:    (0.00 0.00)*
G04 Mirror:    No*
G04 Mode:      Positive*
G04 Rotation:  0*
G04 FullContactRelief:  No*
G04 UndefLineWidth:     6.00*
G04 ================== end FILE IDENTIFICATION RECORD ====================*
%FSLAX35Y35*MOIN*%
%IR0*IPPOS*OFA0.00000B0.00000*MIA0B0*SFA1.00000B1.00000*%
%AMMACRO45*
4,1,40,.013,.017,
-.013,.017,
-.013695,.016939,
-.014368,.016759,
-.015,.016464,
-.015571,.016064,
-.016064,.015571,
-.016464,.015,
-.016759,.014368,
-.016939,.013695,
-.017,.013,
-.017,-.013,
-.016939,-.013695,
-.016759,-.014368,
-.016464,-.015,
-.016064,-.015571,
-.015571,-.016064,
-.015,-.016464,
-.014368,-.016759,
-.013695,-.016939,
-.013,-.017,
.013,-.017,
.013695,-.016939,
.014368,-.016759,
.015,-.016464,
.015571,-.016064,
.016064,-.015571,
.016464,-.015,
.016759,-.014368,
.016939,-.013695,
.017,-.013,
.017,.013,
.016939,.013695,
.016759,.014368,
.016464,.015,
.016064,.015571,
.015571,.016064,
.015,.016464,
.014368,.016759,
.013695,.016939,
.013,.017,
0.0*
%
%ADD45MACRO45*%
%AMMACRO25*
4,1,40,.017,-.013,
.017,.013,
.016939,.013695,
.016759,.014368,
.016464,.015,
.016064,.015571,
.015571,.016064,
.015,.016464,
.014368,.016759,
.013695,.016939,
.013,.017,
-.013,.017,
-.013695,.016939,
-.014368,.016759,
-.015,.016464,
-.015571,.016064,
-.016064,.015571,
-.016464,.015,
-.016759,.014368,
-.016939,.013695,
-.017,.013,
-.017,-.013,
-.016939,-.013695,
-.016759,-.014368,
-.016464,-.015,
-.016064,-.015571,
-.015571,-.016064,
-.015,-.016464,
-.014368,-.016759,
-.013695,-.016939,
-.013,-.017,
.013,-.017,
.013695,-.016939,
.014368,-.016759,
.015,-.016464,
.015571,-.016064,
.016064,-.015571,
.016464,-.015,
.016759,-.014368,
.016939,-.013695,
.017,-.013,
0.0*
%
%ADD25MACRO25*%
%ADD10C,.01*%
%ADD29R,.08X.127*%
%ADD18C,.022*%
%ADD50C,.032*%
%ADD15C,.05*%
%ADD46R,.085X.128*%
%ADD12C,.028*%
%ADD53R,.208X.087*%
%ADD13C,.056*%
%ADD42C,.057*%
%ADD34R,.087X.208*%
%ADD11R,.05X.05*%
%AMMACRO87*
4,1,40,-.014,-.008,
-.014,.008,
-.013939,.008695,
-.013759,.009368,
-.013464,.01,
-.013064,.010571,
-.012571,.011064,
-.012,.011464,
-.011368,.011759,
-.010695,.011939,
-.01,.012,
.01,.012,
.010695,.011939,
.011368,.011759,
.012,.011464,
.012571,.011064,
.013064,.010571,
.013464,.01,
.013759,.009368,
.013939,.008695,
.014,.008,
.014,-.008,
.013939,-.008695,
.013759,-.009368,
.013464,-.01,
.013064,-.010571,
.012571,-.011064,
.012,-.011464,
.011368,-.011759,
.010695,-.011939,
.01,-.012,
-.01,-.012,
-.010695,-.011939,
-.011368,-.011759,
-.012,-.011464,
-.012571,-.011064,
-.013064,-.010571,
-.013464,-.01,
-.013759,-.009368,
-.013939,-.008695,
-.014,-.008,
0.0*
%
%ADD87MACRO87*%
%AMMACRO80*
4,1,40,-.007,-.0225,
-.008389,-.022378,
-.009736,-.022018,
-.011,-.021428,
-.012142,-.020628,
-.013128,-.019642,
-.013928,-.0185,
-.014518,-.017236,
-.014878,-.015889,
-.015,-.0145,
-.015,.0145,
-.014878,.015889,
-.014518,.017236,
-.013928,.0185,
-.013128,.019642,
-.012142,.020628,
-.011,.021428,
-.009736,.022018,
-.008389,.022378,
-.007,.0225,
.007,.0225,
.008389,.022378,
.009736,.022018,
.011,.021428,
.012142,.020628,
.013128,.019642,
.013928,.0185,
.014518,.017236,
.014878,.015889,
.015,.0145,
.015,-.0145,
.014878,-.015889,
.014518,-.017236,
.013928,-.0185,
.013128,-.019642,
.012142,-.020628,
.011,-.021428,
.009736,-.022018,
.008389,-.022378,
.007,-.0225,
-.007,-.0225,
0.0*
%
%ADD80MACRO80*%
%AMMACRO37*
4,1,40,.011,-.007,
.011,.007,
.010939,.007695,
.010759,.008368,
.010464,.009,
.010064,.009571,
.009571,.010064,
.009,.010464,
.008368,.010759,
.007695,.010939,
.007,.011,
-.007,.011,
-.007695,.010939,
-.008368,.010759,
-.009,.010464,
-.009571,.010064,
-.010064,.009571,
-.010464,.009,
-.010759,.008368,
-.010939,.007695,
-.011,.007,
-.011,-.007,
-.010939,-.007695,
-.010759,-.008368,
-.010464,-.009,
-.010064,-.009571,
-.009571,-.010064,
-.009,-.010464,
-.008368,-.010759,
-.007695,-.010939,
-.007,-.011,
.007,-.011,
.007695,-.010939,
.008368,-.010759,
.009,-.010464,
.009571,-.010064,
.010064,-.009571,
.010464,-.009,
.010759,-.008368,
.010939,-.007695,
.011,-.007,
0.0*
%
%ADD37MACRO37*%
%AMMACRO23*
4,1,40,.007,.011,
-.007,.011,
-.007695,.010939,
-.008368,.010759,
-.009,.010464,
-.009571,.010064,
-.010064,.009571,
-.010464,.009,
-.010759,.008368,
-.010939,.007695,
-.011,.007,
-.011,-.007,
-.010939,-.007695,
-.010759,-.008368,
-.010464,-.009,
-.010064,-.009571,
-.009571,-.010064,
-.009,-.010464,
-.008368,-.010759,
-.007695,-.010939,
-.007,-.011,
.007,-.011,
.007695,-.010939,
.008368,-.010759,
.009,-.010464,
.009571,-.010064,
.010064,-.009571,
.010464,-.009,
.010759,-.008368,
.010939,-.007695,
.011,-.007,
.011,.007,
.010939,.007695,
.010759,.008368,
.010464,.009,
.010064,.009571,
.009571,.010064,
.009,.010464,
.008368,.010759,
.007695,.010939,
.007,.011,
0.0*
%
%ADD23MACRO23*%
%AMMACRO84*
4,1,22,.007,.0145,
.007695,.014439,
.008368,.014259,
.009,.013964,
.009571,.013564,
.010064,.013071,
.010464,.0125,
.010759,.011868,
.010939,.011195,
.011,.0105,
.011,-.0145,
-.011,-.0145,
-.011,.0105,
-.010939,.011195,
-.010759,.011868,
-.010464,.0125,
-.010064,.013071,
-.009571,.013564,
-.009,.013964,
-.008368,.014259,
-.007695,.014439,
-.007,.0145,
.007,.0145,
0.0*
%
%ADD84MACRO84*%
%AMMACRO68*
4,1,40,-.012,.008,
-.012,-.008,
-.011939,-.008695,
-.011759,-.009368,
-.011464,-.01,
-.011064,-.010571,
-.010571,-.011064,
-.01,-.011464,
-.009368,-.011759,
-.008695,-.011939,
-.008,-.012,
.008,-.012,
.008695,-.011939,
.009368,-.011759,
.01,-.011464,
.010571,-.011064,
.011064,-.010571,
.011464,-.01,
.011759,-.009368,
.011939,-.008695,
.012,-.008,
.012,.008,
.011939,.008695,
.011759,.009368,
.011464,.01,
.011064,.010571,
.010571,.011064,
.01,.011464,
.009368,.011759,
.008695,.011939,
.008,.012,
-.008,.012,
-.008695,.011939,
-.009368,.011759,
-.01,.011464,
-.010571,.011064,
-.011064,.010571,
-.011464,.01,
-.011759,.009368,
-.011939,.008695,
-.012,.008,
0.0*
%
%ADD68MACRO68*%
%AMMACRO40*
4,1,40,.008,.012,
-.008,.012,
-.008695,.011939,
-.009368,.011759,
-.01,.011464,
-.010571,.011064,
-.011064,.010571,
-.011464,.01,
-.011759,.009368,
-.011939,.008695,
-.012,.008,
-.012,-.008,
-.011939,-.008695,
-.011759,-.009368,
-.011464,-.01,
-.011064,-.010571,
-.010571,-.011064,
-.01,-.011464,
-.009368,-.011759,
-.008695,-.011939,
-.008,-.012,
.008,-.012,
.008695,-.011939,
.009368,-.011759,
.01,-.011464,
.010571,-.011064,
.011064,-.010571,
.011464,-.01,
.011759,-.009368,
.011939,-.008695,
.012,-.008,
.012,.008,
.011939,.008695,
.011759,.009368,
.011464,.01,
.011064,.010571,
.010571,.011064,
.01,.011464,
.009368,.011759,
.008695,.011939,
.008,.012,
0.0*
%
%ADD40MACRO40*%
%AMMACRO36*
4,1,40,-.013,-.017,
.013,-.017,
.013695,-.016939,
.014368,-.016759,
.015,-.016464,
.015571,-.016064,
.016064,-.015571,
.016464,-.015,
.016759,-.014368,
.016939,-.013695,
.017,-.013,
.017,.013,
.016939,.013695,
.016759,.014368,
.016464,.015,
.016064,.015571,
.015571,.016064,
.015,.016464,
.014368,.016759,
.013695,.016939,
.013,.017,
-.013,.017,
-.013695,.016939,
-.014368,.016759,
-.015,.016464,
-.015571,.016064,
-.016064,.015571,
-.016464,.015,
-.016759,.014368,
-.016939,.013695,
-.017,.013,
-.017,-.013,
-.016939,-.013695,
-.016759,-.014368,
-.016464,-.015,
-.016064,-.015571,
-.015571,-.016064,
-.015,-.016464,
-.014368,-.016759,
-.013695,-.016939,
-.013,-.017,
0.0*
%
%ADD36MACRO36*%
%AMMACRO43*
4,1,40,-.017,.013,
-.017,-.013,
-.016939,-.013695,
-.016759,-.014368,
-.016464,-.015,
-.016064,-.015571,
-.015571,-.016064,
-.015,-.016464,
-.014368,-.016759,
-.013695,-.016939,
-.013,-.017,
.013,-.017,
.013695,-.016939,
.014368,-.016759,
.015,-.016464,
.015571,-.016064,
.016064,-.015571,
.016464,-.015,
.016759,-.014368,
.016939,-.013695,
.017,-.013,
.017,.013,
.016939,.013695,
.016759,.014368,
.016464,.015,
.016064,.015571,
.015571,.016064,
.015,.016464,
.014368,.016759,
.013695,.016939,
.013,.017,
-.013,.017,
-.013695,.016939,
-.014368,.016759,
-.015,.016464,
-.015571,.016064,
-.016064,.015571,
-.016464,.015,
-.016759,.014368,
-.016939,.013695,
-.017,.013,
0.0*
%
%ADD43MACRO43*%
%AMMACRO91*
4,1,25,-.26969,-.01299,
-.26969,-.83465,
.26969,-.83465,
.26969,.83465,
-.26969,.83465,
-.26969,.12087,
-.22638,.12087,
-.214758,.119853,
-.203489,.116834,
-.192915,.111903,
-.183358,.105211,
-.175109,.096962,
-.168417,.087405,
-.163486,.076831,
-.160467,.065562,
-.15945,.05394,
-.160467,.042318,
-.163486,.031049,
-.168417,.020475,
-.175109,.010918,
-.183358,.002669,
-.192915,-.004023,
-.203489,-.008954,
-.214758,-.011973,
-.22638,-.01299,
-.26969,-.01299,
0.0*
%
%ADD91MACRO91*%
%AMMACRO38*
4,1,40,.011,-.007,
.011,.007,
.010939,.007695,
.010759,.008368,
.010464,.009,
.010064,.009571,
.009571,.010064,
.009,.010464,
.008368,.010759,
.007695,.010939,
.007,.011,
-.007,.011,
-.007695,.010939,
-.008368,.010759,
-.009,.010464,
-.009571,.010064,
-.010064,.009571,
-.010464,.009,
-.010759,.008368,
-.010939,.007695,
-.011,.007,
-.011,-.007,
-.010939,-.007695,
-.010759,-.008368,
-.010464,-.009,
-.010064,-.009571,
-.009571,-.010064,
-.009,-.010464,
-.008368,-.010759,
-.007695,-.010939,
-.007,-.011,
.007,-.011,
.007695,-.010939,
.008368,-.010759,
.009,-.010464,
.009571,-.010064,
.010064,-.009571,
.010464,-.009,
.010759,-.008368,
.010939,-.007695,
.011,-.007,
0.0*
%
%ADD38MACRO38*%
%AMMACRO26*
4,1,40,.007,.011,
-.007,.011,
-.007695,.010939,
-.008368,.010759,
-.009,.010464,
-.009571,.010064,
-.010064,.009571,
-.010464,.009,
-.010759,.008368,
-.010939,.007695,
-.011,.007,
-.011,-.007,
-.010939,-.007695,
-.010759,-.008368,
-.010464,-.009,
-.010064,-.009571,
-.009571,-.010064,
-.009,-.010464,
-.008368,-.010759,
-.007695,-.010939,
-.007,-.011,
.007,-.011,
.007695,-.010939,
.008368,-.010759,
.009,-.010464,
.009571,-.010064,
.010064,-.009571,
.010464,-.009,
.010759,-.008368,
.010939,-.007695,
.011,-.007,
.011,.007,
.010939,.007695,
.010759,.008368,
.010464,.009,
.010064,.009571,
.009571,.010064,
.009,.010464,
.008368,.010759,
.007695,.010939,
.007,.011,
0.0*
%
%ADD26MACRO26*%
%AMMACRO85*
4,1,22,.011,.0145,
.011,-.0105,
.010939,-.011195,
.010759,-.011868,
.010464,-.0125,
.010064,-.013071,
.009571,-.013564,
.009,-.013964,
.008368,-.014259,
.007695,-.014439,
.007,-.0145,
-.007,-.0145,
-.007695,-.014439,
-.008368,-.014259,
-.009,-.013964,
-.009571,-.013564,
-.010064,-.013071,
-.010464,-.0125,
-.010759,-.011868,
-.010939,-.011195,
-.011,-.0105,
-.011,.0145,
.011,.0145,
0.0*
%
%ADD85MACRO85*%
%AMMACRO67*
4,1,40,-.012,.008,
-.012,-.008,
-.011939,-.008695,
-.011759,-.009368,
-.011464,-.01,
-.011064,-.010571,
-.010571,-.011064,
-.01,-.011464,
-.009368,-.011759,
-.008695,-.011939,
-.008,-.012,
.008,-.012,
.008695,-.011939,
.009368,-.011759,
.01,-.011464,
.010571,-.011064,
.011064,-.010571,
.011464,-.01,
.011759,-.009368,
.011939,-.008695,
.012,-.008,
.012,.008,
.011939,.008695,
.011759,.009368,
.011464,.01,
.011064,.010571,
.010571,.011064,
.01,.011464,
.009368,.011759,
.008695,.011939,
.008,.012,
-.008,.012,
-.008695,.011939,
-.009368,.011759,
-.01,.011464,
-.010571,.011064,
-.011064,.010571,
-.011464,.01,
-.011759,.009368,
-.011939,.008695,
-.012,.008,
0.0*
%
%ADD67MACRO67*%
%AMMACRO39*
4,1,40,.008,.012,
-.008,.012,
-.008695,.011939,
-.009368,.011759,
-.01,.011464,
-.010571,.011064,
-.011064,.010571,
-.011464,.01,
-.011759,.009368,
-.011939,.008695,
-.012,.008,
-.012,-.008,
-.011939,-.008695,
-.011759,-.009368,
-.011464,-.01,
-.011064,-.010571,
-.010571,-.011064,
-.01,-.011464,
-.009368,-.011759,
-.008695,-.011939,
-.008,-.012,
.008,-.012,
.008695,-.011939,
.009368,-.011759,
.01,-.011464,
.010571,-.011064,
.011064,-.010571,
.011464,-.01,
.011759,-.009368,
.011939,-.008695,
.012,-.008,
.012,.008,
.011939,.008695,
.011759,.009368,
.011464,.01,
.011064,.010571,
.010571,.011064,
.01,.011464,
.009368,.011759,
.008695,.011939,
.008,.012,
0.0*
%
%ADD39MACRO39*%
%AMMACRO30*
4,1,40,-.013,-.017,
.013,-.017,
.013695,-.016939,
.014368,-.016759,
.015,-.016464,
.015571,-.016064,
.016064,-.015571,
.016464,-.015,
.016759,-.014368,
.016939,-.013695,
.017,-.013,
.017,.013,
.016939,.013695,
.016759,.014368,
.016464,.015,
.016064,.015571,
.015571,.016064,
.015,.016464,
.014368,.016759,
.013695,.016939,
.013,.017,
-.013,.017,
-.013695,.016939,
-.014368,.016759,
-.015,.016464,
-.015571,.016064,
-.016064,.015571,
-.016464,.015,
-.016759,.014368,
-.016939,.013695,
-.017,.013,
-.017,-.013,
-.016939,-.013695,
-.016759,-.014368,
-.016464,-.015,
-.016064,-.015571,
-.015571,-.016064,
-.015,-.016464,
-.014368,-.016759,
-.013695,-.016939,
-.013,-.017,
0.0*
%
%ADD30MACRO30*%
%AMMACRO44*
4,1,40,-.017,.013,
-.017,-.013,
-.016939,-.013695,
-.016759,-.014368,
-.016464,-.015,
-.016064,-.015571,
-.015571,-.016064,
-.015,-.016464,
-.014368,-.016759,
-.013695,-.016939,
-.013,-.017,
.013,-.017,
.013695,-.016939,
.014368,-.016759,
.015,-.016464,
.015571,-.016064,
.016064,-.015571,
.016464,-.015,
.016759,-.014368,
.016939,-.013695,
.017,-.013,
.017,.013,
.016939,.013695,
.016759,.014368,
.016464,.015,
.016064,.015571,
.015571,.016064,
.015,.016464,
.014368,.016759,
.013695,.016939,
.013,.017,
-.013,.017,
-.013695,.016939,
-.014368,.016759,
-.015,.016464,
-.015571,.016064,
-.016064,.015571,
-.016464,.015,
-.016759,.014368,
-.016939,.013695,
-.017,.013,
0.0*
%
%ADD44MACRO44*%
%ADD49R,.135X.101*%
%ADD90R,.022X.04*%
%ADD74R,.106X.142*%
%ADD59R,.04X.023*%
%ADD71R,.06X.012*%
%ADD70R,.012X.06*%
%ADD79R,.04X.016*%
%ADD76R,.014X.06*%
%ADD27R,.045X.03*%
%AMMACRO61*
4,1,40,.013,-.023,
-.013,-.023,
-.013695,-.022939,
-.014368,-.022759,
-.015,-.022464,
-.015571,-.022064,
-.016064,-.021571,
-.016464,-.021,
-.016759,-.020368,
-.016939,-.019695,
-.017,-.019,
-.017,.019,
-.016939,.019695,
-.016759,.020368,
-.016464,.021,
-.016064,.021571,
-.015571,.022064,
-.015,.022464,
-.014368,.022759,
-.013695,.022939,
-.013,.023,
.013,.023,
.013695,.022939,
.014368,.022759,
.015,.022464,
.015571,.022064,
.016064,.021571,
.016464,.021,
.016759,.020368,
.016939,.019695,
.017,.019,
.017,-.019,
.016939,-.019695,
.016759,-.020368,
.016464,-.021,
.016064,-.021571,
.015571,-.022064,
.015,-.022464,
.014368,-.022759,
.013695,-.022939,
.013,-.023,
0.0*
%
%ADD61MACRO61*%
%ADD16R,.03X.045*%
%ADD88R,.03X.046*%
%ADD47R,.03X.064*%
%ADD82R,.045X.016*%
%ADD81R,.016X.045*%
%ADD75R,.08X.071*%
%ADD17R,.05X.065*%
%ADD57R,.065X.05*%
%ADD86R,.071X.063*%
%ADD73R,.065X.025*%
%ADD31R,.055X.035*%
%ADD14C,.315*%
%ADD65R,.09X.045*%
%ADD63R,.045X.055*%
%ADD62R,.035X.055*%
%ADD56R,.048X.016*%
%ADD72R,.055X.045*%
%ADD55R,.016X.048*%
%ADD48R,.197X.205*%
%ADD41R,.081X.065*%
%ADD54R,.065X.081*%
%ADD78R,.055X.0615*%
%ADD22R,.09X.095*%
%AMMACRO89*
4,1,40,.007,.0225,
.008389,.022378,
.009736,.022018,
.011,.021428,
.012142,.020628,
.013128,.019642,
.013928,.0185,
.014518,.017236,
.014878,.015889,
.015,.0145,
.015,-.0145,
.014878,-.015889,
.014518,-.017236,
.013928,-.0185,
.013128,-.019642,
.012142,-.020628,
.011,-.021428,
.009736,-.022018,
.008389,-.022378,
.007,-.0225,
-.007,-.0225,
-.008389,-.022378,
-.009736,-.022018,
-.011,-.021428,
-.012142,-.020628,
-.013128,-.019642,
-.013928,-.0185,
-.014518,-.017236,
-.014878,-.015889,
-.015,-.0145,
-.015,.0145,
-.014878,.015889,
-.014518,.017236,
-.013928,.0185,
-.013128,.019642,
-.012142,.020628,
-.011,.021428,
-.009736,.022018,
-.008389,.022378,
-.007,.0225,
.007,.0225,
0.0*
%
%ADD89MACRO89*%
%ADD69C,.375*%
%ADD64R,.095X.09*%
%ADD83R,.128X.128*%
%AMMACRO60*
4,1,40,-.017,-.019,
-.017,.019,
-.016939,.019695,
-.016759,.020368,
-.016464,.021,
-.016064,.021571,
-.015571,.022064,
-.015,.022464,
-.014368,.022759,
-.013695,.022939,
-.013,.023,
.013,.023,
.013695,.022939,
.014368,.022759,
.015,.022464,
.015571,.022064,
.016064,.021571,
.016464,.021,
.016759,.020368,
.016939,.019695,
.017,.019,
.017,-.019,
.016939,-.019695,
.016759,-.020368,
.016464,-.021,
.016064,-.021571,
.015571,-.022064,
.015,-.022464,
.014368,-.022759,
.013695,-.022939,
.013,-.023,
-.013,-.023,
-.013695,-.022939,
-.014368,-.022759,
-.015,-.022464,
-.015571,-.022064,
-.016064,-.021571,
-.016464,-.021,
-.016759,-.020368,
-.016939,-.019695,
-.017,-.019,
0.0*
%
%ADD60MACRO60*%
%ADD77R,.055X.06176*%
%ADD58R,.059X.089*%
%AMMACRO52*
4,1,40,-.008,-.012,
.008,-.012,
.008695,-.011939,
.009368,-.011759,
.01,-.011464,
.010571,-.011064,
.011064,-.010571,
.011464,-.01,
.011759,-.009368,
.011939,-.008695,
.012,-.008,
.012,.008,
.011939,.008695,
.011759,.009368,
.011464,.01,
.011064,.010571,
.010571,.011064,
.01,.011464,
.009368,.011759,
.008695,.011939,
.008,.012,
-.008,.012,
-.008695,.011939,
-.009368,.011759,
-.01,.011464,
-.010571,.011064,
-.011064,.010571,
-.011464,.01,
-.011759,.009368,
-.011939,.008695,
-.012,.008,
-.012,-.008,
-.011939,-.008695,
-.011759,-.009368,
-.011464,-.01,
-.011064,-.010571,
-.010571,-.011064,
-.01,-.011464,
-.009368,-.011759,
-.008695,-.011939,
-.008,-.012,
0.0*
%
%ADD52MACRO52*%
%AMMACRO33*
4,1,40,.012,-.008,
.012,.008,
.011939,.008695,
.011759,.009368,
.011464,.01,
.011064,.010571,
.010571,.011064,
.01,.011464,
.009368,.011759,
.008695,.011939,
.008,.012,
-.008,.012,
-.008695,.011939,
-.009368,.011759,
-.01,.011464,
-.010571,.011064,
-.011064,.010571,
-.011464,.01,
-.011759,.009368,
-.011939,.008695,
-.012,.008,
-.012,-.008,
-.011939,-.008695,
-.011759,-.009368,
-.011464,-.01,
-.011064,-.010571,
-.010571,-.011064,
-.01,-.011464,
-.009368,-.011759,
-.008695,-.011939,
-.008,-.012,
.008,-.012,
.008695,-.011939,
.009368,-.011759,
.01,-.011464,
.010571,-.011064,
.011064,-.010571,
.011464,-.01,
.011759,-.009368,
.011939,-.008695,
.012,-.008,
0.0*
%
%ADD33MACRO33*%
%AMMACRO28*
4,1,40,-.007,-.011,
.007,-.011,
.007695,-.010939,
.008368,-.010759,
.009,-.010464,
.009571,-.010064,
.010064,-.009571,
.010464,-.009,
.010759,-.008368,
.010939,-.007695,
.011,-.007,
.011,.007,
.010939,.007695,
.010759,.008368,
.010464,.009,
.010064,.009571,
.009571,.010064,
.009,.010464,
.008368,.010759,
.007695,.010939,
.007,.011,
-.007,.011,
-.007695,.010939,
-.008368,.010759,
-.009,.010464,
-.009571,.010064,
-.010064,.009571,
-.010464,.009,
-.010759,.008368,
-.010939,.007695,
-.011,.007,
-.011,-.007,
-.010939,-.007695,
-.010759,-.008368,
-.010464,-.009,
-.010064,-.009571,
-.009571,-.010064,
-.009,-.010464,
-.008368,-.010759,
-.007695,-.010939,
-.007,-.011,
0.0*
%
%ADD28MACRO28*%
%AMMACRO19*
4,1,40,-.011,.007,
-.011,-.007,
-.010939,-.007695,
-.010759,-.008368,
-.010464,-.009,
-.010064,-.009571,
-.009571,-.010064,
-.009,-.010464,
-.008368,-.010759,
-.007695,-.010939,
-.007,-.011,
.007,-.011,
.007695,-.010939,
.008368,-.010759,
.009,-.010464,
.009571,-.010064,
.010064,-.009571,
.010464,-.009,
.010759,-.008368,
.010939,-.007695,
.011,-.007,
.011,.007,
.010939,.007695,
.010759,.008368,
.010464,.009,
.010064,.009571,
.009571,.010064,
.009,.010464,
.008368,.010759,
.007695,.010939,
.007,.011,
-.007,.011,
-.007695,.010939,
-.008368,.010759,
-.009,.010464,
-.009571,.010064,
-.010064,.009571,
-.010464,.009,
-.010759,.008368,
-.010939,.007695,
-.011,.007,
0.0*
%
%ADD19MACRO19*%
%AMMACRO35*
4,1,40,.013,.017,
-.013,.017,
-.013695,.016939,
-.014368,.016759,
-.015,.016464,
-.015571,.016064,
-.016064,.015571,
-.016464,.015,
-.016759,.014368,
-.016939,.013695,
-.017,.013,
-.017,-.013,
-.016939,-.013695,
-.016759,-.014368,
-.016464,-.015,
-.016064,-.015571,
-.015571,-.016064,
-.015,-.016464,
-.014368,-.016759,
-.013695,-.016939,
-.013,-.017,
.013,-.017,
.013695,-.016939,
.014368,-.016759,
.015,-.016464,
.015571,-.016064,
.016064,-.015571,
.016464,-.015,
.016759,-.014368,
.016939,-.013695,
.017,-.013,
.017,.013,
.016939,.013695,
.016759,.014368,
.016464,.015,
.016064,.015571,
.015571,.016064,
.015,.016464,
.014368,.016759,
.013695,.016939,
.013,.017,
0.0*
%
%ADD35MACRO35*%
%AMMACRO24*
4,1,40,.017,-.013,
.017,.013,
.016939,.013695,
.016759,.014368,
.016464,.015,
.016064,.015571,
.015571,.016064,
.015,.016464,
.014368,.016759,
.013695,.016939,
.013,.017,
-.013,.017,
-.013695,.016939,
-.014368,.016759,
-.015,.016464,
-.015571,.016064,
-.016064,.015571,
-.016464,.015,
-.016759,.014368,
-.016939,.013695,
-.017,.013,
-.017,-.013,
-.016939,-.013695,
-.016759,-.014368,
-.016464,-.015,
-.016064,-.015571,
-.015571,-.016064,
-.015,-.016464,
-.014368,-.016759,
-.013695,-.016939,
-.013,-.017,
.013,-.017,
.013695,-.016939,
.014368,-.016759,
.015,-.016464,
.015571,-.016064,
.016064,-.015571,
.016464,-.015,
.016759,-.014368,
.016939,-.013695,
.017,-.013,
0.0*
%
%ADD24MACRO24*%
%AMMACRO66*
4,1,25,.26969,-.01299,
.26969,-.83465,
-.26969,-.83465,
-.26969,.83465,
.26969,.83465,
.26969,.12087,
.22638,.12087,
.214758,.119853,
.203489,.116834,
.192915,.111903,
.183358,.105211,
.175109,.096962,
.168417,.087405,
.163486,.076831,
.160467,.065562,
.15945,.05394,
.160467,.042318,
.163486,.031049,
.168417,.020475,
.175109,.010918,
.183358,.002669,
.192915,-.004023,
.203489,-.008954,
.214758,-.011973,
.22638,-.01299,
.26969,-.01299,
0.0*
%
%ADD66MACRO66*%
%AMMACRO51*
4,1,40,-.008,-.012,
.008,-.012,
.008695,-.011939,
.009368,-.011759,
.01,-.011464,
.010571,-.011064,
.011064,-.010571,
.011464,-.01,
.011759,-.009368,
.011939,-.008695,
.012,-.008,
.012,.008,
.011939,.008695,
.011759,.009368,
.011464,.01,
.011064,.010571,
.010571,.011064,
.01,.011464,
.009368,.011759,
.008695,.011939,
.008,.012,
-.008,.012,
-.008695,.011939,
-.009368,.011759,
-.01,.011464,
-.010571,.011064,
-.011064,.010571,
-.011464,.01,
-.011759,.009368,
-.011939,.008695,
-.012,.008,
-.012,-.008,
-.011939,-.008695,
-.011759,-.009368,
-.011464,-.01,
-.011064,-.010571,
-.010571,-.011064,
-.01,-.011464,
-.009368,-.011759,
-.008695,-.011939,
-.008,-.012,
0.0*
%
%ADD51MACRO51*%
%AMMACRO32*
4,1,40,.012,-.008,
.012,.008,
.011939,.008695,
.011759,.009368,
.011464,.01,
.011064,.010571,
.010571,.011064,
.01,.011464,
.009368,.011759,
.008695,.011939,
.008,.012,
-.008,.012,
-.008695,.011939,
-.009368,.011759,
-.01,.011464,
-.010571,.011064,
-.011064,.010571,
-.011464,.01,
-.011759,.009368,
-.011939,.008695,
-.012,.008,
-.012,-.008,
-.011939,-.008695,
-.011759,-.009368,
-.011464,-.01,
-.011064,-.010571,
-.010571,-.011064,
-.01,-.011464,
-.009368,-.011759,
-.008695,-.011939,
-.008,-.012,
.008,-.012,
.008695,-.011939,
.009368,-.011759,
.01,-.011464,
.010571,-.011064,
.011064,-.010571,
.011464,-.01,
.011759,-.009368,
.011939,-.008695,
.012,-.008,
0.0*
%
%ADD32MACRO32*%
%AMMACRO21*
4,1,40,-.007,-.011,
.007,-.011,
.007695,-.010939,
.008368,-.010759,
.009,-.010464,
.009571,-.010064,
.010064,-.009571,
.010464,-.009,
.010759,-.008368,
.010939,-.007695,
.011,-.007,
.011,.007,
.010939,.007695,
.010759,.008368,
.010464,.009,
.010064,.009571,
.009571,.010064,
.009,.010464,
.008368,.010759,
.007695,.010939,
.007,.011,
-.007,.011,
-.007695,.010939,
-.008368,.010759,
-.009,.010464,
-.009571,.010064,
-.010064,.009571,
-.010464,.009,
-.010759,.008368,
-.010939,.007695,
-.011,.007,
-.011,-.007,
-.010939,-.007695,
-.010759,-.008368,
-.010464,-.009,
-.010064,-.009571,
-.009571,-.010064,
-.009,-.010464,
-.008368,-.010759,
-.007695,-.010939,
-.007,-.011,
0.0*
%
%ADD21MACRO21*%
%AMMACRO20*
4,1,40,-.011,.007,
-.011,-.007,
-.010939,-.007695,
-.010759,-.008368,
-.010464,-.009,
-.010064,-.009571,
-.009571,-.010064,
-.009,-.010464,
-.008368,-.010759,
-.007695,-.010939,
-.007,-.011,
.007,-.011,
.007695,-.010939,
.008368,-.010759,
.009,-.010464,
.009571,-.010064,
.010064,-.009571,
.010464,-.009,
.010759,-.008368,
.010939,-.007695,
.011,-.007,
.011,.007,
.010939,.007695,
.010759,.008368,
.010464,.009,
.010064,.009571,
.009571,.010064,
.009,.010464,
.008368,.010759,
.007695,.010939,
.007,.011,
-.007,.011,
-.007695,.010939,
-.008368,.010759,
-.009,.010464,
-.009571,.010064,
-.010064,.009571,
-.010464,.009,
-.010759,.008368,
-.010939,.007695,
-.011,.007,
0.0*
%
%ADD20MACRO20*%
%ADD92C,.02*%
%ADD93C,.012*%
%ADD94C,.04*%
%ADD95C,.014*%
%ADD96C,.015*%
%ADD97C,.016*%
%ADD98C,.025*%
%ADD99C,.018*%
%ADD100C,.006*%
%ADD101C,.0055*%
%ADD111C,.05204*%
%ADD107C,.08004*%
%ADD109C,.08104*%
%ADD108R,.13204X.13204*%
%ADD105C,.15006*%
%ADD103C,.12306*%
%ADD106C,.33904*%
%ADD104C,.13906*%
%ADD102C,.16606*%
%ADD110C,.39904*%
G75*
%LPD*%
G75*
G36*
G01X43000Y1037202D02*
X40476D01*
Y1037498D01*
X34745Y1043229D01*
X34787Y1043348D01*
G03X32890Y1047930I-3488J1240D01*
G01X32776Y1047984D01*
Y1049538D01*
X31993Y1050320D01*
G02X32180Y1050991I283J283D01*
G03X28452Y1056953I-881J3596D01*
G02X27862Y1056926I-307J256D01*
G01X25876Y1058912D01*
Y1074137D01*
X31526Y1079787D01*
Y1081468D01*
X31624Y1081527D01*
G03X32402Y1082900I-824J1374D01*
G01Y1084300D01*
G03X30800Y1085902I-1602J0D01*
G01X29400D01*
G03X27798Y1084300I0J-1602D01*
G01Y1082900D01*
G03X28487Y1081584I1601J0D01*
G01X28574Y1081524D01*
Y1081011D01*
X24809Y1077246D01*
G02X24126Y1077529I-283J283D01*
G01Y1090382D01*
X27820D01*
Y1095784D01*
X25844D01*
Y1099770D01*
X25934Y1099829D01*
G03X26696Y1103396I-1434J2171D01*
G01X26665Y1103504D01*
G02X26864Y1103704I200J0D01*
G01X26879Y1103703D01*
G03X27000Y1103698I127J1597D01*
G01X28400D01*
G03X28926Y1103787I-1J1602D01*
G01X28958Y1103798D01*
X37636D01*
X37690Y1103756D01*
G03X38333Y1108216I1610J2044D01*
G01X38298Y1108202D01*
X28958D01*
X28926Y1108213D01*
G03X28400Y1108302I-527J-1513D01*
G01X27000D01*
G03X26000Y1107951I1J-1602D01*
G03X25000Y1108302I-1001J-1251D01*
G01X23600D01*
G03X21998Y1106700I0J-1602D01*
G01Y1105300D01*
G03X22458Y1104177I1601J0D01*
G02X22483Y1103644I-285J-280D01*
G03X22821Y1100013I2017J-1643D01*
G01X22892Y1099953D01*
Y1095784D01*
X20916D01*
Y1090382D01*
X21174D01*
Y1056963D01*
X29822Y1048314D01*
Y1047984D01*
X29708Y1047930D01*
G03X32538Y1041099I1591J-3342D01*
G01X32657Y1041141D01*
X35914Y1037884D01*
G02X35631Y1037202I-283J-282D01*
G01X34548D01*
Y1029798D01*
X43000D01*
Y1026202D01*
X34548D01*
Y1024948D01*
G02X34207Y1024806I-200J0D01*
G01X34138Y1024875D01*
X34125Y1024929D01*
G03X30971Y1021775I-2525J-629D01*
G01X31025Y1021762D01*
X32488Y1020298D01*
X34548D01*
Y1018798D01*
X43000D01*
Y1015500D01*
X48000Y1010500D01*
X54262D01*
X54438Y1010324D01*
X56176D01*
X56198Y1010302D01*
Y1008848D01*
X57651D01*
X59500Y1007000D01*
Y1004000D01*
X61530Y1001970D01*
X61542Y1001950D01*
G03X61922Y1001532I1357J852D01*
G01X62000Y1001472D01*
Y1001128D01*
X61922Y1001068D01*
G03X61298Y999800I978J-1269D01*
G01Y997976D01*
X55768D01*
X55709Y998042D01*
G03X51760Y995969I-1709J-1542D01*
G02X51371Y995476I-389J-93D01*
G01X39488D01*
X38173Y994161D01*
X38073Y994175D01*
G03X40275Y991973I-373J-2575D01*
G01X40261Y992073D01*
X40712Y992524D01*
X96612D01*
X117812Y1013724D01*
X125432D01*
X125491Y1013658D01*
G03Y1016742I1709J1542D01*
G01X125432Y1016676D01*
X116588D01*
X95388Y995476D01*
X67001D01*
G02X66701Y996141I0J400D01*
G03X67102Y997200I-1201J1060D01*
G01Y997500D01*
X67935D01*
G03X68000Y997498I82J1599D01*
G01X69400D01*
G03X71002Y999100I0J1602D01*
G01Y1000502D01*
X72000Y1001500D01*
X97000D01*
X102000Y1006500D01*
Y1051146D01*
X102067Y1051206D01*
G03X102602Y1052400I-1067J1195D01*
G01Y1055000D01*
G03X102209Y1056050I-1602J-1D01*
G03X102602Y1057100I-1209J1051D01*
G01Y1059700D01*
G03X102067Y1060894I-1602J-1D01*
G01X102000Y1060954D01*
Y1112000D01*
X104000Y1114000D01*
X142935D01*
G03X143000Y1113998I82J1599D01*
G01X145600D01*
G03X145665Y1114000I-17J1601D01*
G01X201192D01*
X203692Y1111500D01*
Y528392D01*
X202600Y527300D01*
X173700D01*
X173000Y528000D01*
Y529544D01*
G02X173587Y529898I400J0D01*
G03X175429Y534725I1213J2302D01*
G01X175375Y534738D01*
X175312Y534802D01*
X174849D01*
G03X174751I-49J-2602D01*
G01X173000D01*
Y535535D01*
G03X173002Y535600I-1599J82D01*
G01Y537200D01*
G03X173000Y537265I-1601J-17D01*
G01Y538000D01*
X172000Y539000D01*
X168500D01*
X167500Y540000D01*
Y545000D01*
X168149Y545648D01*
X176052D01*
Y545771D01*
G02X176734Y546054I400J0D01*
G01X180294Y542494D01*
X180289Y542406D01*
G03X182470Y544587I2299J-118D01*
G01X182382Y544582D01*
X176388Y550576D01*
X176052D01*
Y552552D01*
X168737D01*
X168602Y552687D01*
Y554600D01*
G03X167000Y556202I-1602J0D01*
G01X165087D01*
X161776Y559512D01*
Y559612D01*
X161335Y560053D01*
G02X161378Y560656I283J283D01*
G03X159882Y564799I-1378J1844D01*
G01X159794Y564794D01*
X158576Y566012D01*
Y572700D01*
G02X158768Y572900I200J0D01*
G03X160302Y574500I-67J1600D01*
G01Y575900D01*
G03X159951Y576900I-1602J-1D01*
G03X160302Y577900I-1251J1001D01*
G01Y579300D01*
G03X158700Y580902I-1602J0D01*
G01X158312D01*
X156633Y582581D01*
X156619Y582606D01*
G03X153494Y579481I-2019J-1106D01*
G01X153519Y579467D01*
X155953Y577034D01*
X155964Y577017D01*
G03X156049Y576900I1337J882D01*
G03X155698Y575900I1251J-1001D01*
G01Y574937D01*
X155624Y574862D01*
Y569020D01*
G02X155019Y568676I-400J0D01*
G03X154200Y568902I-820J-1376D01*
G01X152800D01*
G03X151413Y568100I1J-1602D01*
G01X151399Y568077D01*
X151239Y567917D01*
X151002Y568155D01*
Y572473D01*
X151080Y572533D01*
G03X151407Y576370I-1580J2067D01*
G02X151414Y576650I146J136D01*
G03X151902Y577800I-1114J1151D01*
G01Y579400D01*
G03X150300Y581002I-1602J0D01*
G01X148700D01*
G03X148598Y580998I12J-1602D01*
G01X148508Y580992D01*
X148200Y581300D01*
Y583400D01*
X150202Y585402D01*
G02X150807Y585355I282J-283D01*
G03X152100Y584698I1293J944D01*
G01X153500D01*
G03X154500Y585049I-1J1602D01*
G03X155500Y584698I1001J1251D01*
G01X156900D01*
G03X158484Y586065I0J1601D01*
G01X158494Y586130D01*
X161452Y589088D01*
Y589577D01*
X161460Y589604D01*
G03X159146Y592550I-2210J646D01*
G02X158845Y593232I-18J400D01*
G01X160736Y595123D01*
Y595937D01*
X164398Y599598D01*
X174815D01*
X175216Y600000D01*
X178500D01*
X186500Y608000D01*
Y648500D01*
X185396Y649604D01*
Y649918D01*
X163312Y672002D01*
X156498D01*
X155000Y673500D01*
Y676500D01*
X155769Y677269D01*
X155819Y677283D01*
G03X157417Y678881I-619J2217D01*
G01X157431Y678931D01*
X160500Y682000D01*
X174000D01*
X180000Y688000D01*
Y703500D01*
X179800Y703700D01*
X179971Y703871D01*
X180011Y703887D01*
G03X176293Y707225I-1011J2613D01*
G01X176254Y707076D01*
X170522D01*
Y714306D01*
X159038D01*
Y706976D01*
X157726D01*
Y714306D01*
X156871D01*
G02X156588Y714988I0J400D01*
G01X163650Y722050D01*
X166550D01*
X168500Y724000D01*
Y728102D01*
X173076D01*
Y736506D01*
X164106D01*
X163900Y736300D01*
Y729400D01*
X163600Y729100D01*
X160900D01*
X160500Y729500D01*
Y736400D01*
X160000Y736900D01*
X154500D01*
X154106Y736506D01*
X153924D01*
Y736323D01*
X153550Y735950D01*
Y726550D01*
X152300Y725300D01*
X143100D01*
X141300Y727100D01*
X138102D01*
Y733502D01*
X137602D01*
Y735266D01*
X152734Y750398D01*
X157927D01*
X157954Y750390D01*
G03Y754810I646J2210D01*
G01X157927Y754802D01*
X150910D01*
X133198Y737090D01*
Y733502D01*
X132698D01*
Y730602D01*
X127365D01*
X127307Y730657D01*
G03X126200Y731102I-1108J-1157D01*
G01X123600D01*
G03X121998Y729500I0J-1602D01*
G01Y727666D01*
G02X121316Y727383I-400J0D01*
G01X120498Y728202D01*
X115502D01*
X113798Y726498D01*
Y723002D01*
X118002Y718798D01*
X120502D01*
X125298Y714002D01*
Y705502D01*
X127002Y703798D01*
X138600D01*
Y698900D01*
X140800Y696700D01*
X141499D01*
G02X141898Y696300I-1J-400D01*
G01Y694700D01*
G03X142676Y693327I1602J1D01*
G01X142774Y693268D01*
Y690388D01*
X142798Y690363D01*
Y686298D01*
X148202D01*
Y688513D01*
X148642Y688954D01*
X148875Y688721D01*
X148829Y688599D01*
G03X152072Y685749I2149J-824D01*
G01X152116Y685774D01*
X152368D01*
X152427Y685676D01*
G03X152549Y685500I1374J822D01*
G03X152198Y684500I1251J-1001D01*
G01Y684198D01*
X152000Y684000D01*
Y683338D01*
X151524Y682862D01*
Y677023D01*
X150500Y676000D01*
X149500D01*
X144500Y681000D01*
X144326D01*
Y685702D01*
X138924D01*
Y680423D01*
X138481Y679981D01*
X137366Y681096D01*
X132000D01*
Y693500D01*
X131000Y694500D01*
X117758D01*
Y694867D01*
X113133D01*
X113000Y695000D01*
X109500D01*
X109367Y694867D01*
X108854D01*
Y694354D01*
X108500Y694000D01*
Y674013D01*
X107788Y673302D01*
X105788D01*
X103736Y671250D01*
G02X103073Y671408I-283J283D01*
G03X98515Y672157I-2473J-808D01*
G01X98455Y672076D01*
X96963D01*
X96917Y672212D01*
G03X95400Y673302I-1517J-511D01*
G01X94682D01*
Y674500D01*
X97500D01*
X98000Y675000D01*
Y694500D01*
X97658Y694842D01*
Y694866D01*
X97634D01*
X96000Y696500D01*
X88317D01*
X88258Y696593D01*
G03X84005Y696796I-2198J-1393D01*
G02X83480Y696701I-316J246D01*
G03X82644Y696936I-835J-1366D01*
G01X81244D01*
G03X79642Y695335I0J-1602D01*
G01Y693935D01*
G03X79767Y693316I1602J1D01*
G02X79370Y692762I-369J-155D01*
G03X79256Y692766I-113J-1597D01*
G01X77863D01*
X77832Y692929D01*
G03X76588Y694561I-2261J-433D01*
G01X76476Y694616D01*
Y699638D01*
X77037Y700198D01*
X78000D01*
Y699500D01*
X85000D01*
X88500Y703000D01*
X89696D01*
X89752Y702952D01*
G03X92748I1498J1748D01*
G01X92804Y703000D01*
X93000D01*
X94500Y704500D01*
Y710798D01*
X109498D01*
X112102Y713402D01*
Y761311D01*
X112213Y761366D01*
G03X113102Y762800I-712J1434D01*
G01Y765400D01*
G03X112694Y766467I-1602J-1D01*
G02Y766733I150J133D01*
G03X113102Y767800I-1194J1068D01*
G01Y770400D01*
G03X112213Y771834I-1601J0D01*
G01X112102Y771889D01*
Y813098D01*
X107498Y817702D01*
X88502D01*
X87198Y816398D01*
Y789698D01*
X86500Y789000D01*
X69500D01*
X60000Y779500D01*
X20500D01*
X19790Y780210D01*
X19814Y780317D01*
G03X19519Y782901I-3908J863D01*
G01X19500Y782942D01*
Y783500D01*
X17500Y785500D01*
X11500D01*
X10500Y784500D01*
Y776699D01*
X8798Y774998D01*
Y767002D01*
X10500Y765301D01*
Y735000D01*
X11000Y734500D01*
X43500D01*
X61750Y716250D01*
X76500D01*
X77000Y715750D01*
Y708500D01*
X78500Y707000D01*
Y705191D01*
G02X78060Y704793I-400J0D01*
G03X77900Y704802I-170J-1592D01*
G01X76500D01*
G03X75701Y704588I1J-1602D01*
G02X75102Y704935I-199J347D01*
G01Y706700D01*
G03X73500Y708302I-1602J0D01*
G01X70900D01*
G03X69833Y707894I1J-1602D01*
G02X69567I-133J150D01*
G03X68500Y708302I-1068J-1194D01*
G01X65900D01*
G03X64298Y706700I0J-1602D01*
G01Y704100D01*
G03X64726Y703011I1602J1D01*
G01X64857Y702870D01*
X61827Y699840D01*
X58398D01*
G03X58277Y699876I-720J-2199D01*
G01X56152Y702002D01*
X51969D01*
G02X51603Y702564I-1J400D01*
G03X49173Y705779I-2103J936D01*
G02X48729Y706075I-57J396D01*
G03X44791Y707042I-2229J-575D01*
G01X44732Y706976D01*
X41913D01*
X31598Y696662D01*
Y688313D01*
X32648Y687263D01*
Y685998D01*
X39148D01*
Y683438D01*
X42663D01*
X45218Y680884D01*
G02X44935Y680202I-283J-282D01*
G01X37312D01*
X31802Y685712D01*
Y686600D01*
G03X30200Y688202I-1602J0D01*
G01X27600D01*
G03X26500Y687764I1J-1602D01*
G03X25400Y688202I-1101J-1164D01*
G01X22800D01*
G03X21198Y686600I0J-1602D01*
G01Y684000D01*
G03X22800Y682398I1602J0D01*
G01X25400D01*
G03X26500Y682836I-1J1602D01*
G03X27600Y682398I1101J1164D01*
G01X28888D01*
X35488Y675798D01*
X35816D01*
G02X35957Y675457I0J-200D01*
G01X35500Y675000D01*
Y645549D01*
G02X34926Y645188I-400J-1D01*
G03X29579Y613090I-7367J-15267D01*
G02X29910Y612410I48J-397D01*
G01X7300Y589800D01*
Y513900D01*
X6500Y513100D01*
Y506500D01*
X8000Y505000D01*
X12949D01*
G02X13218Y504304I0J-400D01*
G03X18594I2688J-2965D01*
G02X18863Y505000I269J296D01*
G01X25000D01*
X30000Y500000D01*
Y487500D01*
X37500Y480000D01*
Y462950D01*
G02X36770Y462724I-400J0D01*
G03Y453338I-6849J-4693D01*
G02X37500Y453112I330J-226D01*
G01Y356500D01*
X37282Y356282D01*
X35002Y358562D01*
X35000Y358643D01*
G03X33533Y355611I-3701J-80D01*
G01X33672Y355716D01*
X36500Y352888D01*
Y350040D01*
X34696D01*
X34642Y350154D01*
G03Y346972I-3343J-1591D01*
G01X34696Y347086D01*
X36500D01*
Y338000D01*
X35225Y336725D01*
X34745Y337205D01*
X34787Y337324D01*
G03X32538Y335075I-3488J1239D01*
G01X32657Y335117D01*
X33137Y334637D01*
X32500Y334000D01*
X23900D01*
X23872Y334168D01*
G03X19328I-2272J-368D01*
G01X19300Y334000D01*
X16500D01*
X14500Y332000D01*
Y303500D01*
X17500Y300500D01*
X19228D01*
X19257Y300491D01*
G03X20763I753J2491D01*
G01X20792Y300500D01*
X35500D01*
X36000Y300000D01*
Y287500D01*
X40500Y283000D01*
X68200D01*
Y278779D01*
G02X67517Y278496I-400J0D01*
G01X63812Y282202D01*
X61558D01*
X61526Y282213D01*
G03X61000Y282302I-527J-1513D01*
G01X59600D01*
G03X58600Y281951I1J-1602D01*
G03X57600Y282302I-1001J-1251D01*
G01X56200D01*
G03X54854Y281568I0J-1601D01*
G01X54795Y281476D01*
X47388D01*
X46006Y280094D01*
X45918Y280099D01*
G03X48099Y277918I-118J-2299D01*
G01X48094Y278006D01*
X48612Y278524D01*
X54795D01*
X54854Y278432D01*
G03X56200Y277698I1346J867D01*
G01X57600D01*
G03X58600Y278049I-1J1602D01*
G03X58877Y277871I1000J1251D01*
G02X58908Y277533I-90J-179D01*
G03X58481Y274289I1392J-1833D01*
G01X58524Y274234D01*
Y271129D01*
G02X58031Y270740I-400J0D01*
G03X55201Y268382I-531J-2240D01*
G01X55206Y268294D01*
X52824Y265912D01*
Y265405D01*
X52732Y265346D01*
G03X51998Y264000I867J-1346D01*
G01Y262600D01*
G03X52349Y261600I1602J1D01*
G03X51998Y260600I1251J-1001D01*
G01Y259200D01*
G03X52732Y257854I1601J0D01*
G01X52824Y257795D01*
Y254288D01*
X53298Y253813D01*
Y251500D01*
G03X54900Y249898I1602J0D01*
G01X57213D01*
X59338Y247774D01*
X59826D01*
X60437Y247163D01*
X60394Y247044D01*
G03X60298Y246500I1506J-546D01*
G01Y245100D01*
G03X60387Y244574I1602J1D01*
G01X60398Y244542D01*
Y242838D01*
X60594Y242643D01*
G02X60452Y242302I-142J-141D01*
G01X60300D01*
G03X59220Y241882I1J-1602D01*
G02X58680I-270J296D01*
G03X57600Y242302I-1081J-1182D01*
G01X56200D01*
G03X54598Y240700I0J-1602D01*
G01Y239300D01*
G03X56200Y237698I1602J0D01*
G01X57600D01*
G03X58456Y237946I0J1601D01*
G01X58563Y237977D01*
G02X58763Y237777I0J-200D01*
G01X58756Y237724D01*
G03X58704Y237434I1544J-426D01*
G01X58698Y237361D01*
X56343Y235007D01*
X56318Y234993D01*
G03X55418Y234103I1106J-2019D01*
G01X55416Y234099D01*
X55332Y234016D01*
X45828D01*
X44729Y235114D01*
G03X40490Y233419I-2009J-1124D01*
G01X40496Y233370D01*
X40360Y233180D01*
G03X38803Y231146I740J-2180D01*
G02X38344Y230776I-399J26D01*
G03X38118Y226201I-344J-2276D01*
G01X38206Y226206D01*
X38838Y225574D01*
X41800D01*
Y182501D01*
X41768Y182451D01*
G03Y179949I1932J-1251D01*
G01X41800Y179899D01*
Y178876D01*
X34513D01*
X34457Y178982D01*
G03X33560Y175897I-2032J-1082D01*
G01X33606Y175924D01*
X36598D01*
G02X36998Y175520I0J-400D01*
G03X38020Y173587I2302J-20D01*
G01X38036Y173576D01*
X48224Y163388D01*
Y160888D01*
X54599Y154513D01*
X54606Y154442D01*
G03X56200Y152998I1594J158D01*
G01X57600D01*
G03X59202Y154600I0J1602D01*
G01Y156063D01*
X60137Y156998D01*
X61000D01*
G03X62332Y157711I0J1601D01*
G01X62391Y157800D01*
X73600D01*
G02X73852Y157089I0J-400D01*
G03X73191Y156222I1448J-1789D01*
G01X73176Y156188D01*
X63989Y147002D01*
X58887D01*
X52184Y153704D01*
X52171Y153761D01*
G03X50529Y151040I-2247J-500D01*
G01X50641Y151071D01*
X57663Y144048D01*
X65213D01*
X74359Y153195D01*
X74480Y153149D01*
G03X77566Y155704I820J2151D01*
G02X78243Y156057I394J70D01*
G01X78900Y155400D01*
X109500D01*
X109550Y155450D01*
X113450D01*
X141000Y183000D01*
Y193500D01*
X144900Y197400D01*
X185500D01*
X189000Y200900D01*
Y312500D01*
X178500Y323000D01*
Y426500D01*
X183000Y431000D01*
X186500D01*
X188904Y433404D01*
X189025Y433360D01*
G03X189065Y433345I934J2429D01*
G01X189198Y433298D01*
Y433078D01*
X189190Y433051D01*
G03X193505Y431472I2210J-646D01*
G01X193520Y431506D01*
X196452Y434438D01*
Y435452D01*
X196500Y435500D01*
Y438735D01*
G03X196502Y438800I-1599J82D01*
G01Y440200D01*
G03X196500Y440265I-1601J-17D01*
G01Y441500D01*
X197000Y442000D01*
X201692D01*
X203692Y440000D01*
Y279192D01*
X203346Y278846D01*
X203692Y278500D01*
Y43307D01*
G02X202756Y42371I-936J0D01*
G01X72835D01*
G03X65897Y35433I0J-6938D01*
G01Y3937D01*
G02X64961Y3001I-936J0D01*
G01X3937D01*
G02X3001Y3937I0J936D01*
G01Y1328776D01*
G02X3731Y1329002I400J0D01*
G03Y1348164I13985J9581D01*
G02X3001Y1348390I-330J226D01*
G01Y1964567D01*
G02X3937Y1965503I936J0D01*
G01X64961D01*
G02X65897Y1964567I0J-936D01*
G01Y1933071D01*
G03X72835Y1926133I6938J0D01*
G01X202756D01*
G02X203692Y1925197I0J-936D01*
G01Y1503692D01*
X198000Y1498000D01*
X180500D01*
X177000Y1501500D01*
Y1502778D01*
X177007Y1502804D01*
G03Y1504196I-2507J696D01*
G01X177000Y1504222D01*
Y1508778D01*
X177007Y1508804D01*
G03Y1510196I-2507J696D01*
G01X177000Y1510222D01*
Y1565500D01*
X181000Y1569500D01*
Y1575000D01*
X188500Y1582500D01*
Y1614000D01*
X185500Y1617000D01*
Y1666500D01*
X182500Y1669500D01*
X140000D01*
X132500Y1677000D01*
Y1771500D01*
X135500Y1774500D01*
X140500D01*
X143000Y1777000D01*
Y1780500D01*
X140500Y1783000D01*
X136000D01*
X132500Y1786500D01*
Y1868000D01*
X136500Y1872000D01*
X141000D01*
X145000Y1876000D01*
Y1893000D01*
X141500Y1896500D01*
X113000D01*
X111000Y1898500D01*
Y1917000D01*
X108500Y1919500D01*
X66722D01*
X66696Y1919507D01*
G03X65304I-696J-2507D01*
G01X65278Y1919500D01*
X20280D01*
G02X19883Y1919945I0J400D01*
G03X11929I-3977J449D01*
G02X11532Y1919500I-397J-45D01*
G01X11500D01*
X8000Y1916000D01*
Y1911000D01*
X9000Y1910000D01*
Y1879000D01*
X11000Y1877000D01*
X13785D01*
X13832Y1876971D01*
G03X19889Y1880785I2074J3423D01*
G01X19880Y1880880D01*
X23000Y1884000D01*
Y1885400D01*
X24124Y1886524D01*
X28476D01*
X52500Y1862500D01*
Y1810988D01*
X37269Y1795758D01*
X37175D01*
X31557Y1790139D01*
X31450Y1790163D01*
G03X31100Y1790202I-351J-1563D01*
G01X29500D01*
G03X27898Y1788600I0J-1602D01*
G01Y1787000D01*
G03X28676Y1785627I1602J1D01*
G01X28774Y1785568D01*
Y1784234D01*
X28388Y1783848D01*
X28387D01*
X27016Y1782476D01*
X25302D01*
Y1783952D01*
X17398D01*
Y1778048D01*
X17524D01*
Y1774787D01*
X17519Y1774765D01*
G03X22274Y1772828I2537J-576D01*
G01X22332Y1772924D01*
X25199D01*
G02X25499Y1772259I0J-400D01*
G03X25264Y1771908I1201J-1059D01*
G02X24724Y1771728I-359J177D01*
G03X24000Y1771902I-726J-1428D01*
G01X22600D01*
G03X20998Y1770300I0J-1602D01*
G01Y1768900D01*
G03X22600Y1767298I1602J0D01*
G01X24000D01*
G03X24950Y1767611I-1J1602D01*
G02X25490Y1767551I238J-322D01*
G03X25760Y1767303I1211J1048D01*
G02X25808Y1766696I-234J-324D01*
G01X25206Y1766094D01*
X25118Y1766099D01*
G03X27299Y1763918I-118J-2299D01*
G01X27294Y1764006D01*
X29276Y1765988D01*
Y1766999D01*
G03X30500Y1767540I24J1601D01*
G02X31100I300J-265D01*
G03X32300Y1766998I1201J1060D01*
G01X34900D01*
G03X36502Y1768600I0J1602D01*
G01Y1771200D01*
G03X36428Y1771679I-1602J-2D01*
G02X36810Y1772198I382J119D01*
G01X38133D01*
G02X38416Y1771516I0J-400D01*
G01X37400Y1770500D01*
Y1748700D01*
X39398D01*
Y1748288D01*
X39370Y1748241D01*
G03X43830I2230J-1341D01*
G01X43802Y1748288D01*
Y1748700D01*
X46198D01*
Y1748288D01*
X46170Y1748241D01*
G03X50630I2230J-1341D01*
G01X50602Y1748288D01*
Y1753067D01*
X50596Y1753134D01*
G03X50251Y1754000I-1596J-134D01*
G03X50602Y1755000I-1251J1001D01*
G01Y1756400D01*
G03X49824Y1757773I-1602J-1D01*
G01X49726Y1757832D01*
Y1758068D01*
X49824Y1758127D01*
G03X50602Y1759500I-824J1374D01*
G01Y1761100D01*
G03X50499Y1761664I-1602J-1D01*
G01X50486Y1761734D01*
X50610Y1761919D01*
G03X51200Y1762340I-611J1480D01*
G02X51800I300J-265D01*
G03X53000Y1761798I1201J1060D01*
G01X55600D01*
G03X57202Y1763400I0J1602D01*
G01Y1766000D01*
G03X55600Y1767602I-1602J0D01*
G01X53637D01*
X51702Y1769537D01*
Y1770500D01*
G03X50479Y1772056I-1601J0D01*
G01X50326Y1772093D01*
Y1773000D01*
X54500D01*
X54750Y1773250D01*
X59250Y1768750D01*
Y1751250D01*
X49500Y1741500D01*
Y1638500D01*
X48300Y1637300D01*
Y1602518D01*
X48278Y1602475D01*
G03Y1600125I2322J-1175D01*
G01X48300Y1600082D01*
Y1596518D01*
X48278Y1596475D01*
G03Y1594125I2322J-1175D01*
G01X48300Y1594082D01*
Y1590518D01*
X48278Y1590475D01*
G03Y1588125I2322J-1175D01*
G01X48300Y1588082D01*
Y1584018D01*
X48278Y1583975D01*
G03Y1581625I2322J-1175D01*
G01X48300Y1581582D01*
Y1512000D01*
X53800Y1506500D01*
X99000D01*
X101000Y1504500D01*
Y1497500D01*
X97502Y1494002D01*
X85889D01*
X84425Y1492538D01*
X84371Y1492525D01*
G03X82475Y1490629I629J-2525D01*
G01X82462Y1490575D01*
X82048Y1490162D01*
Y1490048D01*
X81500Y1489500D01*
Y1482000D01*
X83000Y1480500D01*
Y1472058D01*
X82850Y1472019D01*
G03X81029Y1468685I650J-2519D01*
G01X81068Y1468568D01*
X80500Y1468000D01*
Y1459000D01*
X82000D01*
X83000Y1458000D01*
X90500D01*
X91500Y1457000D01*
Y1453500D01*
X91302Y1453302D01*
X90600D01*
G03X89713Y1453033I1J-1602D01*
G01X89663Y1453000D01*
X88566D01*
X88511Y1453043D01*
G03X85289I-1611J-2043D01*
G01X85234Y1453000D01*
X84500D01*
X84000Y1452500D01*
Y1450500D01*
X84496Y1450004D01*
X84511Y1449969D01*
G03X88511Y1448957I2389J1031D01*
G01X88566Y1449000D01*
X89663D01*
X89713Y1448967D01*
G03X90600Y1448698I888J1333D01*
G01X91802D01*
X92500Y1448000D01*
Y1447762D01*
X92489Y1447730D01*
G03X92398Y1447200I1511J-532D01*
G01Y1445800D01*
G03X92489Y1445270I1602J2D01*
G01X92500Y1445238D01*
Y1444162D01*
X92489Y1444130D01*
G03X92398Y1443600I1511J-532D01*
G01Y1442000D01*
G03X92409Y1441816I1602J3D01*
G01X92420Y1441720D01*
X92200Y1441500D01*
X89900D01*
X88800Y1442600D01*
X87298D01*
G03X87102I-98J-2600D01*
G01X86000D01*
X84500Y1441100D01*
Y1440000D01*
X84550Y1439950D01*
Y1438750D01*
X86000Y1437300D01*
X86787D01*
X87288Y1436798D01*
X90042D01*
X90074Y1436787D01*
G03X90600Y1436698I527J1513D01*
G01X92000D01*
G03X92262Y1436720I-3J1602D01*
G01X92363Y1436737D01*
X92500Y1436600D01*
Y1436262D01*
X92489Y1436230D01*
G03X92398Y1435700I1511J-532D01*
G01Y1434100D01*
G03X92489Y1433570I1602J2D01*
G01X92500Y1433538D01*
Y1432862D01*
X92489Y1432830D01*
G03X92398Y1432300I1511J-532D01*
G01Y1431898D01*
X92000Y1431500D01*
X88900D01*
X87000Y1429600D01*
Y1429312D01*
X86976Y1429267D01*
G03X86790Y1427525I2024J-1097D01*
G01X86798Y1427498D01*
Y1425338D01*
X87000Y1425137D01*
Y1418900D01*
X88500Y1417400D01*
X94600D01*
X102166Y1409834D01*
X102073Y1409697D01*
G03X102054Y1409668I1330J-892D01*
G01X101995Y1409576D01*
X101069D01*
X101017Y1409614D01*
G03X101712Y1406131I-1517J-2114D01*
G02X102322Y1406216I340J-211D01*
G03X102422Y1406132I1079J1183D01*
G01X102500Y1406072D01*
Y1399500D01*
X103198Y1398802D01*
Y1395138D01*
X106862D01*
X107000Y1395000D01*
X112500D01*
X113000Y1394500D01*
Y1393476D01*
X98388D01*
X96024Y1391112D01*
Y1381888D01*
X98888Y1379024D01*
X114976D01*
X115000Y1379000D01*
X148000D01*
X151000Y1376000D01*
Y1146500D01*
X144500Y1140000D01*
X137000D01*
X134000Y1143000D01*
Y1159000D01*
X129000Y1164000D01*
X117000D01*
X74500Y1206500D01*
Y1342500D01*
X23500Y1393500D01*
Y1414000D01*
X24500Y1415000D01*
X31000D01*
X31762Y1415762D01*
X31817Y1415775D01*
G03X37517Y1427209I-1896J8083D01*
G01X37500Y1427248D01*
Y1429500D01*
X32000Y1435000D01*
Y1478500D01*
X27000Y1483500D01*
X18858D01*
G02X18590Y1484197I0J400D01*
G03X13222I-2684J2968D01*
G02X12954Y1483500I-268J-297D01*
G01X8500D01*
X7500Y1482500D01*
Y1474000D01*
X10500Y1471000D01*
X13153D01*
G02X13403Y1470288I0J-400D01*
G03X16537Y1463213I2503J-3123D01*
G02X17000Y1462818I63J-395D01*
G01Y1461512D01*
G02X16537Y1461117I-400J0D01*
G03Y1453213I-631J-3952D01*
G02X17000Y1452818I63J-395D01*
G01Y1451512D01*
G02X16537Y1451117I-400J0D01*
G03X15721Y1443167I-630J-3952D01*
G02X15985Y1442485I-19J-399D01*
G01X9500Y1436000D01*
Y1384000D01*
X60000Y1333500D01*
Y1198000D01*
X64500Y1193500D01*
Y1173500D01*
X62000Y1171000D01*
X60500D01*
X59500Y1172000D01*
Y1175500D01*
X39500Y1195500D01*
Y1211000D01*
X26000Y1224500D01*
X19581D01*
G02X19247Y1225120I0J400D01*
G03X12565I-3341J2203D01*
G02X12231Y1224500I-334J-220D01*
G01X7500D01*
X6500Y1223500D01*
Y1187500D01*
X11500Y1182500D01*
X27912D01*
X43000Y1167412D01*
Y1098638D01*
G02X42500Y1098251I-400J0D01*
G03X42361Y1098280I-396J-1552D01*
G01X42298Y1098291D01*
X39289Y1101300D01*
X39268D01*
X39209Y1101365D01*
G03X35931Y1098138I-1709J-1543D01*
G02X35987Y1097617I-272J-293D01*
G03X35698Y1096700I1313J-918D01*
G01Y1095300D01*
G03X35941Y1094453I1602J1D01*
G02X35815Y1093902I-339J-212D01*
G03X34626Y1092080I1385J-2203D01*
G01X34601Y1091910D01*
X28416D01*
Y1086506D01*
X35320D01*
Y1087731D01*
X36727Y1089139D01*
X36827Y1089125D01*
G03X39257Y1090107I373J2575D01*
G02X39974Y1089862I317J-245D01*
G01Y1084912D01*
X29822Y1074761D01*
Y1067984D01*
X29708Y1067930D01*
G03X32890I1591J-3343D01*
G01X32776Y1067984D01*
Y1073537D01*
X42317Y1083079D01*
G02X43000Y1082796I283J-283D01*
G01Y1037202D01*
G37*
G36*
G01X9000Y508000D02*
X7702Y509298D01*
Y512602D01*
X8502Y513402D01*
Y589302D01*
X15316Y596117D01*
X15317Y596118D01*
G03X15382Y596183I-1807J1872D01*
G01X15383Y596184D01*
X33099Y613900D01*
X33142Y613915D01*
G03X39553Y617941I-5582J16007D01*
G01X39612Y618000D01*
X82000D01*
X85550Y614450D01*
Y601950D01*
X82100Y598500D01*
X72602D01*
X72598D01*
G03X72402I-98J-2600D01*
G01X72398D01*
X37000D01*
X21800Y583300D01*
Y579098D01*
X21748Y579041D01*
G03X21747Y575943I1702J-1550D01*
G01X21798Y575885D01*
Y572639D01*
X21796Y572637D01*
Y568963D01*
X21798Y568961D01*
Y564870D01*
X21800Y564869D01*
Y546373D01*
X21796Y546352D01*
G03Y542940I8125J-1706D01*
G01X21800Y542919D01*
Y538000D01*
X21850Y537950D01*
Y530550D01*
X29700Y522700D01*
Y513300D01*
X24400Y508000D01*
X19183D01*
G02X18885Y508667I0J400D01*
G03X12927I-2979J2672D01*
G02X12629Y508000I-298J-267D01*
G01X9000D01*
G37*
G36*
G01X27400Y527300D02*
X27000Y527700D01*
Y534000D01*
X29362Y536362D01*
X29451Y536357D01*
G03X33611Y552083I470J8289D01*
G01X33500Y552139D01*
Y559500D01*
X35000Y561000D01*
X58500D01*
X61000Y563500D01*
X68734D01*
X68789Y563457D01*
G03X72011I1611J2043D01*
G01X72066Y563500D01*
X72500D01*
X75499Y566498D01*
X79502D01*
X81628Y564372D01*
Y557128D01*
X81500Y557000D01*
X75928D01*
X75868Y557078D01*
G03X74600Y557702I-1269J-978D01*
G01X73200D01*
G03X71598Y556100I0J-1602D01*
G01Y555098D01*
X71500Y555000D01*
Y551547D01*
X71473Y551501D01*
G03Y548699I2427J-1401D01*
G01X71500Y548653D01*
Y544562D01*
X71489Y544530D01*
G03X71398Y544000I1511J-532D01*
G01Y542600D01*
G03X71489Y542070I1602J2D01*
G01X71500Y542038D01*
Y541162D01*
X71489Y541130D01*
G03X71398Y540600I1511J-532D01*
G01Y539200D01*
G03X71489Y538670I1602J2D01*
G01X71500Y538638D01*
Y536500D01*
X73500Y534500D01*
X75519D01*
X75578Y534443D01*
G03X76771Y533775I1823J1856D01*
G01X76825Y533762D01*
X78838Y531748D01*
X79133D01*
Y531529D01*
X79129Y531510D01*
G03X79098Y531200I1571J-314D01*
G01Y529800D01*
G03X80700Y528198I1602J0D01*
G01X82100D01*
G03X82475Y528243I-2J1602D01*
G01X82498Y528248D01*
X83283D01*
G02X83566Y527566I0J-400D01*
G01X83300Y527300D01*
X27400D01*
G37*
G36*
G01X62000Y572588D02*
X53489Y564078D01*
X28500D01*
Y566500D01*
X30000Y568000D01*
X34000D01*
X34568Y568568D01*
X34612Y568583D01*
G03X35702Y570100I-511J1517D01*
G01Y571500D01*
G03X35657Y571875I-1602J-2D01*
G01X35652Y571898D01*
Y572152D01*
X38500Y575000D01*
X42546D01*
X42606Y574933D01*
G03X43800Y574398I1195J1067D01*
G01X46400D01*
G03X47594Y574933I-1J1602D01*
G01X47654Y575000D01*
X47837D01*
X47892Y574955D01*
G03X48900Y574598I1008J1245D01*
G01X50300D01*
G03X51308Y574955I0J1602D01*
G01X51363Y575000D01*
X55076D01*
X55131Y574953D01*
G03X58469I1669J1997D01*
G01X58524Y575000D01*
X59738D01*
X59770Y574989D01*
G03X60300Y574898I532J1511D01*
G01X61101D01*
X62000Y574000D01*
Y572588D01*
G37*
G36*
G01X57932Y752480D02*
X66888Y743524D01*
X66976D01*
X68000Y742500D01*
X72062D01*
X72798Y741763D01*
Y740700D01*
G03X74400Y739098I1602J0D01*
G01X75463D01*
X75638Y738924D01*
X77000D01*
Y735000D01*
X78000Y734000D01*
Y730000D01*
X77702Y729702D01*
X76300D01*
G03X75564Y729522I2J-1602D01*
G01X75521Y729500D01*
X74748D01*
X74689Y729564D01*
G03X71638Y729856I-1689J-1564D01*
G02X71002Y730178I-236J323D01*
G01Y730700D01*
G03X69400Y732302I-1602J0D01*
G01X68000D01*
G03X67000Y731951I1J-1602D01*
G03X66000Y732302I-1001J-1251D01*
G01X64600D01*
G03X63407Y731768I1J-1602D01*
G01X63347Y731702D01*
X62205D01*
X53205Y740702D01*
X24798D01*
X20702Y744798D01*
Y748792D01*
X20500Y748993D01*
Y757000D01*
X22000Y758500D01*
X23912D01*
X29932Y752480D01*
X57932D01*
G37*
G36*
G01X73738Y745000D02*
X72262Y746476D01*
X68112D01*
X67000Y747588D01*
Y760000D01*
X63000Y764000D01*
X53601D01*
X53547Y764116D01*
G03X40941I-6303J-2935D01*
G01X40887Y764000D01*
X18748D01*
X18690Y764056D01*
G03X13427Y764323I-2784J-2875D01*
G01X13287Y764213D01*
X10000Y767500D01*
Y774500D01*
X12500Y777000D01*
X60000D01*
X70000Y787000D01*
X81000D01*
X84000Y784000D01*
Y769400D01*
X83300Y768700D01*
Y747300D01*
X81000Y745000D01*
X73738D01*
G37*
G36*
G01X51500Y1038000D02*
X49976Y1039524D01*
Y1171114D01*
X29500Y1191590D01*
Y1204500D01*
X21500Y1212500D01*
X10500D01*
X8000Y1215000D01*
Y1221000D01*
X10000Y1223000D01*
X23000D01*
X37000Y1209000D01*
Y1195000D01*
X58000Y1174000D01*
Y1096552D01*
X57998D01*
Y1084648D01*
X58000D01*
Y1083875D01*
X62500Y1079375D01*
X70625D01*
X71500Y1078500D01*
Y1074152D01*
X70698D01*
Y1065248D01*
X71500D01*
Y1038500D01*
X71000Y1038000D01*
X51500D01*
G37*
G36*
G01X100000Y1140700D02*
X97400Y1143300D01*
Y1150600D01*
X96000Y1152000D01*
Y1164800D01*
X91734Y1169066D01*
X91722Y1169086D01*
G03X90686Y1170122I-2722J-1686D01*
G01X90666Y1170134D01*
X61202Y1199598D01*
Y1333998D01*
X61200Y1333999D01*
Y1334500D01*
X10702Y1384998D01*
Y1435502D01*
X18202Y1443002D01*
Y1443885D01*
X18283Y1443945D01*
G03X18567Y1450154I-2377J3220D01*
G01X18500Y1450214D01*
Y1454116D01*
X18567Y1454176D01*
G03Y1460154I-2661J2989D01*
G01X18500Y1460214D01*
Y1464116D01*
X18567Y1464176D01*
G03Y1470154I-2661J2989D01*
G01X18500Y1470214D01*
Y1470500D01*
X16500Y1472500D01*
X10699D01*
X8702Y1474498D01*
Y1480702D01*
X10000Y1482000D01*
X25000D01*
X30500Y1476500D01*
Y1436000D01*
X25159Y1430659D01*
X25145Y1430649D01*
G03X23130Y1428634I4776J-6791D01*
G01X23120Y1428620D01*
X22000Y1427500D01*
Y1426346D01*
X21991Y1426317D01*
G03Y1421399I7930J-2459D01*
G01X22000Y1421370D01*
Y1393000D01*
X73298Y1341702D01*
Y1206002D01*
X73300Y1206001D01*
Y1205000D01*
X115900Y1162400D01*
X128600D01*
X132500Y1158500D01*
Y1143300D01*
X129900Y1140700D01*
X109552D01*
Y1140802D01*
X100648D01*
Y1140700D01*
X100000D01*
G37*
G36*
G01X67000Y1896500D02*
X57000Y1906500D01*
X50567D01*
X50523Y1906524D01*
G03X43965I-3279J-6131D01*
G01X43921Y1906500D01*
X31000D01*
X28000Y1903500D01*
X18431D01*
X18376Y1903543D01*
G03X13436I-2470J-3149D01*
G01X13381Y1903500D01*
X10500D01*
X10202Y1903798D01*
Y1910498D01*
X9500Y1911199D01*
Y1912500D01*
X12000Y1915000D01*
X19000D01*
X22298Y1918298D01*
X107702D01*
X108500Y1917500D01*
Y1899000D01*
X106000Y1896500D01*
X84552D01*
Y1897202D01*
X75648D01*
Y1896500D01*
X67000D01*
G37*
G36*
G01X52500Y1874000D02*
X31500Y1895000D01*
X26000D01*
X25000Y1896000D01*
Y1899500D01*
X27000Y1901500D01*
X29500D01*
X32500Y1904500D01*
X40894D01*
G02X41240Y1903898I1J-400D01*
G03X53248I6004J-3505D01*
G02X53594Y1904500I345J202D01*
G01X56500D01*
X68000Y1893000D01*
Y1878500D01*
X63500Y1874000D01*
X52500D01*
G37*
G36*
G01X82712Y432598D02*
X85712Y435598D01*
X86702D01*
Y443114D01*
X87552D01*
Y443500D01*
X89078D01*
X89104Y443493D01*
G03X90496I696J2507D01*
G01X90522Y443500D01*
X92948D01*
Y442614D01*
X108500D01*
Y436000D01*
X107500Y435000D01*
X103000D01*
X96818Y428818D01*
X96791Y428804D01*
G03X95696Y427709I1209J-2304D01*
G01X95682Y427682D01*
X95000Y427000D01*
Y375300D01*
X95100Y375200D01*
Y374900D01*
X92500Y372300D01*
Y352700D01*
X94200Y351000D01*
X103500D01*
X106500Y348000D01*
Y316500D01*
X120000Y303000D01*
Y262400D01*
X115314Y257714D01*
G02X114643Y257901I-283J283D01*
G03X107313Y254718I-3934J-973D01*
G02X106978Y254100I-335J-218D01*
G01X104440D01*
G02X104105Y254718I0J400D01*
G03X97313I-3396J2211D01*
G02X96978Y254100I-335J-218D01*
G01X94440D01*
G02X94105Y254718I0J400D01*
G03X87313I-3396J2211D01*
G02X86978Y254100I-335J-218D01*
G01X84440D01*
G02X84105Y254718I0J400D01*
G03X76659Y256818I-3396J2211D01*
G02X75976Y256524I-400J-11D01*
G01X72100Y260400D01*
Y281200D01*
X68800Y284500D01*
X41000D01*
X38000Y287500D01*
Y315115D01*
X44976Y322091D01*
Y322476D01*
X45000Y322500D01*
Y348500D01*
X44976Y348524D01*
Y348588D01*
X38750Y354814D01*
Y435250D01*
X47000Y443500D01*
X65448D01*
Y443114D01*
X81298D01*
Y437412D01*
X80888Y437002D01*
X72388D01*
X68548Y433162D01*
Y432398D01*
X68543Y432375D01*
G03X68498Y432000I1557J-377D01*
G01Y430600D01*
G03X68543Y430225I1602J2D01*
G01X68548Y430202D01*
Y428315D01*
X68531Y428275D01*
G03X73018Y428711I2369J-1075D01*
G01X73217Y429024D01*
G03X73500Y428998I287J1576D01*
G01X74900D01*
G03X75227Y429032I-1J1602D01*
G01X75332Y429054D01*
X75967Y428419D01*
X75981Y428394D01*
G03X79106Y431519I2019J1106D01*
G01X79081Y431533D01*
X78698Y431916D01*
G02X78981Y432598I283J282D01*
G01X82712D01*
G37*
G36*
G01X41750Y444250D02*
X40500Y445500D01*
Y476500D01*
X43000Y479000D01*
X97000D01*
X97250Y478750D01*
X100650D01*
G02X101040Y478260I0J-400D01*
G03X100998Y477900I1559J-364D01*
G01Y475300D01*
G03X102600Y473698I1602J0D01*
G01X105200D01*
G03X106801Y475254I0J1602D01*
G01X106806Y475448D01*
X107427D01*
X107454Y475440D01*
G03X110323Y478246I646J2210D01*
G02X110710Y478750I386J104D01*
G01X120750D01*
X124500Y475000D01*
Y450000D01*
X119046Y444546D01*
X118944Y444564D01*
G03X117237Y444275I-444J-2564D01*
G01X117192Y444250D01*
X108949D01*
X108498Y444702D01*
X46502D01*
X46051Y444250D01*
X41750D01*
G37*
G36*
G01X40000Y480000D02*
X31202Y488798D01*
Y500498D01*
X31000Y500699D01*
Y517500D01*
X31100Y517600D01*
Y521300D01*
X35600Y525800D01*
X87022D01*
X87049Y525792D01*
G03X88351I651J2208D01*
G01X88378Y525800D01*
X91600D01*
X91750Y525650D01*
X96350D01*
X96500Y525800D01*
X111100D01*
X111198Y525898D01*
X152098D01*
X152299Y526100D01*
X155100D01*
X155800Y525400D01*
X173000D01*
X173698Y526098D01*
X202901D01*
X203500Y525500D01*
Y481000D01*
X202500Y480000D01*
X185300D01*
X184300Y481000D01*
Y484900D01*
X183600Y485600D01*
X151400D01*
X150800Y485000D01*
Y481400D01*
X149400Y480000D01*
X143748D01*
X143689Y480064D01*
G03X140311I-1689J-1564D01*
G01X140252Y480000D01*
X99400D01*
X97700Y481700D01*
Y484400D01*
X95800Y486300D01*
X66900D01*
X60802Y480202D01*
X42502D01*
X42301Y480000D01*
X40000D01*
G37*
G36*
G01X68500Y571500D02*
X68000Y572000D01*
Y577500D01*
X71000Y580500D01*
X73500D01*
X74048Y581048D01*
X75602D01*
Y586952D01*
X75500D01*
Y587500D01*
X76500Y588500D01*
X79500D01*
X79930Y588930D01*
X79950Y588942D01*
G03X80458Y589450I-850J1358D01*
G01X80470Y589470D01*
X82000Y591000D01*
Y595000D01*
X85000Y598000D01*
X90000D01*
X90764Y597236D01*
Y596771D01*
G03X90974Y595978I1602J0D01*
G01X91000Y595932D01*
Y595610D01*
X90974Y595564D01*
G03X90764Y594771I1392J-793D01*
G01Y593371D01*
G03X90852Y592845I1601J-2D01*
G01X90864Y592813D01*
Y585223D01*
X95250Y580837D01*
Y579250D01*
X92000Y576000D01*
X89367D01*
X89309Y576056D01*
G03X88200Y576502I-1109J-1156D01*
G01X87455D01*
X87355Y576602D01*
X87005D01*
X85320Y578286D01*
Y579771D01*
X85385Y579831D01*
G03X81853I-1766J1911D01*
G01X81918Y579771D01*
Y576913D01*
X81802Y576859D01*
G03X80327Y574889I1098J-2359D01*
G01X80317Y574824D01*
X78895Y573402D01*
X77900D01*
G03X76892Y573045I0J-1602D01*
G01X76837Y573000D01*
X76567D01*
X76509Y573056D01*
G03X75400Y573502I-1109J-1156D01*
G01X72800D01*
G03X71198Y571900I0J-1602D01*
G01Y571500D01*
X68500D01*
G37*
G36*
G01X47588Y675798D02*
X50967Y672419D01*
X50981Y672394D01*
G03X54692Y671939I2019J1106D01*
G02X55328Y671874I294J-272D01*
G03X55654Y671487I1373J825D01*
G01X55724Y671427D01*
Y670029D01*
X55643Y669969D01*
G03X59285Y666327I1557J-2085D01*
G01X59345Y666408D01*
X60226D01*
G02X60367Y666066I0J-200D01*
G01X60298Y665998D01*
Y655002D01*
X66502Y648798D01*
X67202D01*
X69000Y647000D01*
X77200D01*
X84798Y639402D01*
Y637298D01*
X84850D01*
Y626350D01*
X81000Y622500D01*
X49600D01*
X47200Y624900D01*
Y635000D01*
X36702Y645498D01*
Y674502D01*
X37998Y675798D01*
X47588D01*
G37*
G36*
G01X75587Y677000D02*
X80914Y671673D01*
G02X80667Y670992I-283J-283D01*
G03X79529Y666189I233J-2592D01*
G01X79624Y666130D01*
Y658188D01*
X92324Y645488D01*
Y638500D01*
X86000D01*
Y640500D01*
X76500Y650000D01*
X67000D01*
X61500Y655500D01*
Y665500D01*
X62408Y666408D01*
X62496D01*
X64587Y668498D01*
X65962D01*
X65963Y668500D01*
X66500D01*
X69004Y671004D01*
X71436D01*
Y673437D01*
X71500Y673500D01*
Y677000D01*
X75587D01*
G37*
G36*
G01X52589Y679500D02*
X50013Y682076D01*
X48202D01*
X46352Y683927D01*
Y687442D01*
X39852D01*
Y688558D01*
X46352D01*
Y688751D01*
G02X46693Y688893I200J0D01*
G01X48148Y687437D01*
Y685998D01*
X54648D01*
Y683438D01*
X55137D01*
Y683144D01*
X55063Y683084D01*
G03X54313Y680056I1647J-2015D01*
G02X53945Y679500I-368J-156D01*
G01X52589D01*
G37*
G36*
G01X74899Y702237D02*
X73524Y700862D01*
Y693549D01*
X73503Y693508D01*
G03X73277Y692684I2068J-1010D01*
G01X73262Y692500D01*
X67500D01*
X66208Y691208D01*
X64335D01*
G03X62734Y689606I0J-1601D01*
G01Y688318D01*
X61857Y687442D01*
X55352D01*
Y688558D01*
X61852D01*
Y692562D01*
X60252D01*
Y695438D01*
X63651D01*
X69502Y701288D01*
Y702365D01*
G02X70101Y702712I400J0D01*
G03X70900Y702498I800J1388D01*
G01X73500D01*
G03X74299Y702712I-1J1602D01*
G02X74899Y702365I200J-347D01*
G01Y702237D01*
G37*
G36*
G01X51026Y692562D02*
X46717Y696871D01*
X46742Y696979D01*
G03X46800Y697584I-2242J520D01*
G02X47200Y697998I400J14D01*
G01X54494D01*
X55464Y697029D01*
X55478Y696980D01*
G03X56179Y695897I2206J659D01*
G01X56248Y695837D01*
Y692562D01*
X51026D01*
G37*
G36*
G01X73112Y1566498D02*
X77602Y1570988D01*
Y1571198D01*
X78102D01*
Y1578714D01*
X78952D01*
Y1579000D01*
X89948D01*
Y1578614D01*
X105798D01*
Y1571098D01*
X106298D01*
Y1569673D01*
X106290Y1569646D01*
G03X110710I2210J-646D01*
G01X110702Y1569673D01*
Y1571098D01*
X111202D01*
Y1578614D01*
X112052D01*
Y1579000D01*
X124948D01*
Y1578614D01*
X140798D01*
Y1571098D01*
X141298D01*
Y1568131D01*
X141292Y1568106D01*
G03Y1566934I2226J-586D01*
G01X141298Y1566909D01*
Y1566626D01*
X141485Y1566439D01*
X141499Y1566414D01*
G03X145711Y1568220I2019J1106D01*
G01X145702Y1568250D01*
Y1571098D01*
X146202D01*
Y1578614D01*
X147052D01*
Y1579000D01*
X158948D01*
Y1578614D01*
X174798D01*
Y1571098D01*
X175298D01*
Y1570173D01*
X175290Y1570146D01*
G03X175476Y1568404I2210J-645D01*
G01X175500Y1568359D01*
Y1500000D01*
X179500Y1496000D01*
X198000D01*
X202000Y1500000D01*
X203000D01*
Y1464674D01*
G02X202542Y1464278I-400J0D01*
G03Y1459722I-332J-2278D01*
G02X203000Y1459326I58J-396D01*
G01Y1446695D01*
G02X202570Y1446296I-400J0D01*
G03Y1441704I-170J-2296D01*
G02X203000Y1441305I30J-399D01*
G01Y1427915D01*
G02X202421Y1427558I-400J1D01*
G03Y1423442I-1032J-2058D01*
G02X203000Y1423085I179J-358D01*
G01Y1415468D01*
G02X202437Y1415103I-400J0D01*
G03Y1410897I-937J-2103D01*
G02X203000Y1410532I163J-365D01*
G01Y1390848D01*
G02X202467Y1390471I-400J0D01*
G03Y1386129I-767J-2171D01*
G02X203000Y1385752I133J-377D01*
G01Y1361968D01*
G02X202437Y1361603I-400J0D01*
G03Y1357397I-937J-2103D01*
G02X203000Y1357032I163J-365D01*
G01Y1350421D01*
G02X202319Y1350137I-400J0D01*
G03Y1346863I-1619J-1637D01*
G02X203000Y1346579I281J-284D01*
G01Y1312468D01*
G02X202437Y1312103I-400J0D01*
G03Y1307897I-937J-2103D01*
G02X203000Y1307532I163J-365D01*
G01Y1282700D01*
G02X202585Y1282300I-400J0D01*
G03Y1277700I-85J-2300D01*
G02X203000Y1277300I15J-400D01*
G01Y1248635D01*
G02X202511Y1248245I-400J0D01*
G03Y1243755I-511J-2245D01*
G02X203000Y1243365I89J-390D01*
G01Y1214635D01*
G02X202511Y1214245I-400J0D01*
G03Y1209755I-511J-2245D01*
G02X203000Y1209365I89J-390D01*
G01Y1181700D01*
G02X202585Y1181300I-400J0D01*
G03Y1176700I-85J-2300D01*
G02X203000Y1176300I15J-400D01*
G01Y1149468D01*
G02X202437Y1149103I-400J0D01*
G03Y1144897I-937J-2103D01*
G02X203000Y1144532I163J-365D01*
G01Y1119500D01*
X198702Y1115202D01*
X103502D01*
X103501Y1115200D01*
X101700D01*
X100000Y1113500D01*
Y1008000D01*
X94702Y1002702D01*
X71502D01*
X71400Y1002600D01*
X70919Y1003081D01*
X70949Y1003192D01*
G03X71002Y1003600I-1549J409D01*
G01Y1005000D01*
G03X70556Y1006109I-1602J0D01*
G01X70500Y1006167D01*
Y1014500D01*
X74000Y1018000D01*
Y1018872D01*
X74078Y1018932D01*
G03X74702Y1020200I-978J1269D01*
G01Y1021600D01*
G03X74078Y1022868I-1602J-1D01*
G01X74000Y1022928D01*
Y1023446D01*
X74067Y1023506D01*
G03X74602Y1024700I-1067J1195D01*
G01Y1026100D01*
G03X74067Y1027294I-1602J-1D01*
G01X74000Y1027354D01*
Y1113200D01*
X72000Y1115200D01*
X63600D01*
X62300Y1116500D01*
Y1121200D01*
X62500Y1121400D01*
X65400D01*
X66500Y1122500D01*
Y1128600D01*
X67100Y1129200D01*
X73400D01*
X74200Y1128400D01*
Y1124700D01*
X74500Y1124400D01*
X79446D01*
X79506Y1124334D01*
G03X80698Y1123802I1192J1069D01*
G01X82098D01*
G03X83290Y1124334I0J1601D01*
G01X83350Y1124400D01*
X84600D01*
X85100Y1124900D01*
Y1126500D01*
X85000Y1126600D01*
Y1129000D01*
X86650Y1130650D01*
X90450D01*
X98400Y1138600D01*
X100648D01*
Y1138198D01*
X109552D01*
Y1138600D01*
X146000D01*
X152200Y1144800D01*
Y1146001D01*
X152202Y1146002D01*
Y1360502D01*
X154200Y1362500D01*
X169000D01*
X172000Y1365500D01*
Y1429661D01*
G02X172530Y1430039I400J0D01*
G03X175671Y1433723I845J2461D01*
G01X175648Y1433768D01*
Y1434018D01*
X175946D01*
Y1440920D01*
X173570D01*
Y1450599D01*
X172000Y1452169D01*
Y1464800D01*
X170952Y1465848D01*
Y1468752D01*
X168048D01*
X167800Y1469000D01*
X155000D01*
X147884Y1461884D01*
X147883Y1461883D01*
G03X147810Y1461810I1803J-1876D01*
G01X147809Y1461809D01*
X146602Y1460602D01*
X145158D01*
X145126Y1460613D01*
G03X144600Y1460702I-527J-1513D01*
G01X143200D01*
G03X143127Y1460700I7J-1602D01*
G02X142728Y1461219I-18J399D01*
G03X142802Y1461700I-1528J481D01*
G01Y1463100D01*
G03X142533Y1463987I-1602J-1D01*
G01X142500Y1464037D01*
Y1464763D01*
X142533Y1464813D01*
G03X142802Y1465700I-1333J888D01*
G01Y1467100D01*
G03X142798Y1467202I-1602J-12D01*
G01X142792Y1467292D01*
X144098Y1468598D01*
X144602D01*
Y1469102D01*
X147006Y1471506D01*
G02X147480Y1471831I394J-67D01*
G03X147800Y1471798I323J1569D01*
G01X149200D01*
G03X150792Y1473230I0J1601D01*
G01X150800Y1473300D01*
X151000Y1473500D01*
Y1478778D01*
X151007Y1478804D01*
G03X151064Y1479944I-2507J697D01*
G01X151046Y1480046D01*
X155000Y1484000D01*
Y1494752D01*
X155064Y1494811D01*
G03Y1498189I-1564J1689D01*
G01X155000Y1498248D01*
Y1502000D01*
X147000Y1510000D01*
X136499D01*
X136445Y1510044D01*
G03X133571I-1437J-1799D01*
G01X133517Y1510000D01*
X55000D01*
X49502Y1515498D01*
Y1577002D01*
X51500Y1579000D01*
X56848D01*
Y1578714D01*
X72698D01*
X72699Y1572312D01*
X71288Y1570902D01*
X68373D01*
X68346Y1570910D01*
G03Y1566490I-646J-2210D01*
G01X68373Y1566498D01*
X73112D01*
G37*
G36*
G01X63500Y1081500D02*
X59500Y1085500D01*
Y1112000D01*
X61000Y1113500D01*
X70000D01*
X72798Y1110702D01*
Y1082298D01*
X72000Y1081500D01*
X63500D01*
G37*
G36*
G01X64964Y1140500D02*
X64909Y1140545D01*
G03X63898Y1140904I-1010J-1242D01*
G01X62498D01*
G03X61600Y1140629I-1J-1601D01*
G01X61463Y1140537D01*
X59500Y1142500D01*
Y1155500D01*
X62000Y1158000D01*
X68500D01*
X69024Y1157476D01*
Y1146120D01*
X68999Y1146075D01*
G03X68798Y1145300I1401J-777D01*
G01Y1144237D01*
X68726Y1144164D01*
Y1142298D01*
X67250D01*
Y1140750D01*
X67000Y1140500D01*
X64964D01*
G37*
G36*
G01X139020Y1625327D02*
X136848Y1623154D01*
X135050D01*
Y1619452D01*
X134748D01*
Y1617202D01*
X114902D01*
Y1617748D01*
X114949Y1617804D01*
G03X114845Y1620910I-1749J1496D01*
G02Y1621190I143J140D01*
G03X111704Y1624549I-1645J1610D01*
G01X111648Y1624502D01*
X111095D01*
X109748Y1623154D01*
X106550D01*
Y1619452D01*
X106248D01*
Y1617202D01*
X85016D01*
X84957Y1617289D01*
G03X84705Y1617600I-1908J-1288D01*
G02X84698Y1618148I288J278D01*
G03X82023Y1621787I-1698J1555D01*
G02X81454Y1622150I-169J362D01*
G01Y1623154D01*
X76050D01*
Y1619452D01*
X75748D01*
Y1617202D01*
X54502D01*
X54301Y1617000D01*
X53400D01*
X49502Y1620898D01*
Y1636102D01*
X50750Y1637350D01*
Y1640250D01*
X50702Y1640299D01*
Y1741002D01*
X60452Y1750752D01*
Y1750952D01*
X61000Y1751500D01*
Y1784730D01*
X60970D01*
X60000Y1785700D01*
Y1868000D01*
X66500Y1874500D01*
X121500D01*
X128000Y1868000D01*
Y1785500D01*
X125500Y1783000D01*
X117000D01*
X114500Y1780500D01*
Y1777000D01*
X117000Y1774500D01*
X126000D01*
X128000Y1772500D01*
Y1676500D01*
X137500Y1667000D01*
X181500D01*
X184000Y1664500D01*
Y1620500D01*
X180702Y1617202D01*
X171776D01*
G02X171494Y1617884I1J400D01*
G01X174702Y1621092D01*
Y1624712D01*
X174771Y1624772D01*
G03X171602Y1628104I-1501J1745D01*
G02X171331Y1628087I-145J138D01*
G03X168127Y1624807I-1454J-1784D01*
G01X168174Y1624751D01*
Y1623581D01*
X167748Y1623154D01*
X162550D01*
Y1619452D01*
X162248D01*
Y1617202D01*
X143002D01*
Y1619853D01*
X143065Y1619912D01*
G03X143092Y1623263I-1565J1688D01*
G02X143076Y1623535I138J145D01*
G03X139031Y1625389I-1776J1465D01*
G01X139020Y1625327D01*
G37*
G36*
G01X50000Y1579900D02*
X49502Y1580398D01*
Y1610502D01*
X55000Y1616000D01*
X76050D01*
Y1615550D01*
X75748D01*
Y1613548D01*
X76050D01*
Y1609846D01*
X81454D01*
Y1613547D01*
X81904Y1613998D01*
X82033Y1613935D01*
G03X85345Y1615816I1017J2065D01*
G01X85359Y1616000D01*
X106550D01*
Y1615550D01*
X106248D01*
Y1613548D01*
X106550D01*
Y1609846D01*
X111954D01*
Y1614147D01*
X113806Y1616000D01*
X135050D01*
Y1615550D01*
X134748D01*
Y1613548D01*
X135050D01*
Y1609846D01*
X140454D01*
Y1614047D01*
X142406Y1616000D01*
X162550D01*
Y1615550D01*
X162248D01*
Y1613548D01*
X162550D01*
Y1609846D01*
X167954D01*
Y1614344D01*
X169609Y1616000D01*
X184500D01*
X187298Y1613202D01*
Y1583298D01*
X183900Y1579900D01*
X180202D01*
Y1579902D01*
X175797D01*
X175498Y1580202D01*
X51002D01*
X50701Y1579900D01*
X50000D01*
G37*
G36*
G01X70500Y1876000D02*
X69000Y1877500D01*
Y1877801D01*
X69202Y1878002D01*
Y1892202D01*
X72298Y1895298D01*
X75648D01*
Y1894598D01*
X84552D01*
Y1895298D01*
X106498D01*
X106699Y1895500D01*
X112301D01*
X112502Y1895298D01*
X137702D01*
X143798Y1889202D01*
Y1876798D01*
X143000Y1876000D01*
X70500D01*
G37*
G36*
G01X145500Y251000D02*
X140500Y256000D01*
Y285500D01*
X109500Y316500D01*
Y349000D01*
X111000Y350500D01*
X114500D01*
X117400Y353400D01*
Y373300D01*
X114000Y376700D01*
Y378021D01*
X114022Y378064D01*
G03X114202Y378800I-1422J738D01*
G01Y381400D01*
G03X114022Y382136I-1602J-2D01*
G01X114000Y382179D01*
Y389278D01*
X114007Y389304D01*
G03Y390696I-2507J696D01*
G01X114000Y390722D01*
Y428300D01*
X120898Y435198D01*
X122000D01*
G03X123602Y436800I0J1602D01*
G01Y437901D01*
X128500Y442800D01*
X137448D01*
Y442614D01*
X153298D01*
Y435098D01*
X153798D01*
Y434162D01*
X152739Y433102D01*
X152666Y433096D01*
G03X151800Y432751I134J-1596D01*
G03X150800Y433102I-1001J-1251D01*
G01X149372D01*
X148993Y433481D01*
X148979Y433506D01*
G03X145854Y430381I-2019J-1106D01*
G01X145879Y430367D01*
X147648Y428598D01*
X148842D01*
X148874Y428587D01*
G03X149400Y428498I527J1513D01*
G01X150800D01*
G03X151800Y428849I-1J1602D01*
G03X152800Y428498I1001J1251D01*
G01X154200D01*
G03X155784Y429865I0J1601D01*
G01X155794Y429930D01*
X158202Y432338D01*
Y435098D01*
X158702D01*
Y437298D01*
X160156D01*
X160207Y437175D01*
G03X163241Y440694I2405J994D01*
G01X163187Y440707D01*
X162193Y441702D01*
X158702D01*
Y442614D01*
X159552D01*
Y442800D01*
X165448D01*
Y442614D01*
X176500D01*
Y442500D01*
X179500D01*
X180000Y442000D01*
Y431500D01*
X177500Y429000D01*
Y427199D01*
X177298Y426998D01*
Y322502D01*
X177500Y322301D01*
Y321500D01*
X177300Y321300D01*
X187000Y311600D01*
Y252500D01*
X185500Y251000D01*
X145500D01*
G37*
G36*
G01X94099Y352800D02*
X93702Y353198D01*
Y371802D01*
X96302Y374402D01*
Y375698D01*
X96202Y375798D01*
Y426502D01*
X103498Y433798D01*
X107998D01*
X108199Y434000D01*
X112000D01*
X113500Y432500D01*
Y429499D01*
X112798Y428798D01*
Y376202D01*
X113500Y375501D01*
Y375500D01*
X116000Y373000D01*
Y353699D01*
X115101Y352800D01*
X94099D01*
G37*
G36*
G01X186702Y443500D02*
Y443902D01*
X177702D01*
Y444002D01*
X131498D01*
X128500Y447000D01*
Y476000D01*
X131000Y478500D01*
X139691D01*
X139705Y478316D01*
G03X140894Y476481I2295J184D01*
G01X140919Y476467D01*
X143088Y474298D01*
X144235D01*
X144293Y474243D01*
G03X145400Y473798I1108J1157D01*
G01X148000D01*
G03X149602Y475400I0J1602D01*
G01Y478000D01*
G03X149599Y478080I-1601J-20D01*
G02X149999Y478500I400J20D01*
G01X202000D01*
X203500Y477000D01*
Y445000D01*
X202000Y443500D01*
X186702D01*
G37*
G36*
G01X136483Y537370D02*
X137854Y535998D01*
X146002D01*
X148899Y533101D01*
X148898Y533018D01*
G03X150871Y530475I2602J-18D01*
G01X150925Y530462D01*
X151138Y530248D01*
X153000D01*
Y528500D01*
X151600Y527100D01*
X99500D01*
X98250Y528350D01*
Y529119D01*
X98267Y529157D01*
G03X98402Y529800I-1467J644D01*
G01Y531200D01*
G03X98051Y532200I-1602J-1D01*
G03X98402Y533200I-1251J1001D01*
G01Y534600D01*
G03X98357Y534975I-1602J-2D01*
G01X98352Y534998D01*
Y536322D01*
X98368Y536360D01*
G03X98502Y537000I-1468J641D01*
G01Y538600D01*
G03X98368Y539240I-1602J-1D01*
G01X98352Y539278D01*
Y539438D01*
X98434Y539498D01*
G03X99354Y542466I-1534J2102D01*
G02X99740Y542999I377J133D01*
G03X102033Y544264I60J2601D01*
G02X102659Y544341I343J-206D01*
G01X103500Y543500D01*
X108500D01*
X112000Y547000D01*
Y549143D01*
X112056Y549201D01*
G03X112616Y550178I-1656J1598D01*
G01X112657Y550324D01*
X113532D01*
X113591Y550258D01*
G03Y553342I1709J1542D01*
G01X113532Y553276D01*
X113212D01*
X111052Y555437D01*
Y561500D01*
X127000D01*
X127290Y561790D01*
X127305D01*
X131927Y566412D01*
G02X132609Y566165I283J-283D01*
G03X137267Y564820I2591J235D01*
G01X137327Y564898D01*
X137611D01*
X137666Y564787D01*
G03X139100Y563898I1434J712D01*
G01X141700D01*
G03X142745Y564287I-1J1602D01*
G01X142886Y564408D01*
X145428Y561866D01*
Y556928D01*
X143000Y554500D01*
Y544426D01*
X138945D01*
X138888Y544532D01*
G03X138347Y545117I-1409J-761D01*
G01X138256Y545176D01*
Y546142D01*
X138343Y546202D01*
G03X138250Y550901I-1572J2319D01*
G01X138156Y550960D01*
Y551666D01*
X138247Y551725D01*
G03X138980Y553071I-869J1346D01*
G01Y554471D01*
G03X137379Y556072I-1601J0D01*
G01X135979D01*
G03X134378Y554471I0J-1601D01*
G01Y553071D01*
G03X135111Y551725I1602J0D01*
G01X135202Y551666D01*
Y550845D01*
X135120Y550785D01*
G03X135214Y546192I1651J-2264D01*
G01X135302Y546132D01*
Y545176D01*
X135211Y545117D01*
G03X134478Y543771I869J-1346D01*
G01Y542371D01*
G03X134482Y542252I1601J-6D01*
G02X134083Y541822I-399J-30D01*
G01X133173D01*
X133146Y541831D01*
G03Y537411I-646J-2210D01*
G01X133173Y537420D01*
X135681D01*
X135704Y537414D01*
G03X136079Y537370I373J1557D01*
G01X136483D01*
G37*
G36*
G01X134398Y575110D02*
X125481Y566192D01*
X117307D01*
X117000Y566500D01*
Y571000D01*
X118892Y572892D01*
X118985Y572798D01*
X121627D01*
X121654Y572790D01*
G03Y577210I646J2210D01*
G01X121627Y577202D01*
X120809D01*
X119002Y579009D01*
Y583938D01*
X119013Y583970D01*
G03X119102Y584496I-1513J527D01*
G01Y585602D01*
X119824Y586324D01*
X119919Y586313D01*
G03X120100Y586302I188J1591D01*
G01X121500D01*
G03X122580Y586722I-1J1602D01*
G02X123120I270J-296D01*
G03X124200Y586302I1081J1182D01*
G01X125600D01*
G03X126081Y586376I0J1602D01*
G02X126600Y585975I120J-381D01*
G03X126598Y585896I1600J-80D01*
G01Y584496D01*
G03X126687Y583970I1602J1D01*
G01X126698Y583938D01*
Y581173D01*
X126690Y581146D01*
G03X131110I2210J-646D01*
G01X131102Y581173D01*
Y583938D01*
X131113Y583970D01*
G03X131202Y584496I-1513J527D01*
G01Y585896D01*
G03X131099Y586459I-1602J-2D01*
G02X131474Y587000I374J141D01*
G01X132000D01*
X136500Y591500D01*
X137928D01*
X137988Y591429D01*
G03X142886Y593761I2147J1800D01*
G01X142866Y593866D01*
X145059Y596059D01*
X145109Y596074D01*
G03X145142Y601446I-780J2691D01*
G01X145000Y601490D01*
Y608526D01*
G02X145433Y608925I400J0D01*
G03X145565Y608920I127J1596D01*
G01X146628D01*
X146778Y608770D01*
X146779D01*
X148000Y607549D01*
Y606000D01*
X148314Y605687D01*
Y605520D01*
X148480D01*
X149000Y605000D01*
X154500D01*
X155000Y604500D01*
Y604000D01*
X155634Y603367D01*
Y602779D01*
G03X156256Y601512I1601J0D01*
G01X156334Y601452D01*
Y596947D01*
X153388Y594002D01*
X145688D01*
X134398Y582712D01*
Y575110D01*
G37*
G36*
G01X99702Y581500D02*
Y582612D01*
X95266Y587047D01*
Y591500D01*
X98000D01*
X98305Y591805D01*
X98358Y591819D01*
G03X99517Y592978I-393J1552D01*
G01X99531Y593031D01*
X101841Y595341D01*
X101970Y595274D01*
G03X102700Y595098I730J1426D01*
G01X104300D01*
G03X104708Y595151I-1J1602D01*
G01X104819Y595181D01*
X105220Y594780D01*
X105209Y594684D01*
G03X105198Y594500I1591J-187D01*
G01Y592900D01*
G03X106800Y591298I1602J0D01*
G01X107024D01*
Y588112D01*
X104924Y586012D01*
Y582682D01*
X104839Y582623D01*
G03X103988Y581614I1499J-2127D01*
G01X103934Y581500D01*
X99702D01*
G37*
G36*
G01X121588Y668500D02*
X121462Y668626D01*
X118432D01*
X118373Y668724D01*
G03X118251Y668900I-1374J-822D01*
G03X118602Y669900I-1251J1001D01*
G01Y671300D01*
G03X117000Y672902I-1602J0D01*
G01X115600D01*
G03X114600Y672551I1J-1602D01*
G03X114248Y672765I-1001J-1250D01*
G02X114127Y673413I162J366D01*
G01X115213Y674500D01*
X129500D01*
X130875Y675875D01*
X130917Y675891D01*
G03X131752Y676593I-551J1504D01*
G01X131809Y676692D01*
X134500D01*
Y673500D01*
X129500Y668500D01*
X122358D01*
X122348Y668501D01*
G03X121828I-260J-2589D01*
G01X121818Y668500D01*
X121588D01*
G37*
G36*
G01X88912Y669902D02*
X83687Y675127D01*
G02X83952Y675809I283J283D01*
G03X86138Y678358I-102J2300D01*
G02X86545Y678802I398J44D01*
G03X87497Y678984I53J2301D01*
G01X87534Y679000D01*
X88000D01*
Y676000D01*
X88754Y675246D01*
Y674964D01*
X89036D01*
X89500Y674500D01*
X91730D01*
Y671932D01*
X92398Y671263D01*
Y670300D01*
G03X92408Y670124I1602J3D01*
G01X92409Y670113D01*
Y669902D01*
X88912D01*
G37*
G36*
G01X91000Y712000D02*
X88400Y714600D01*
Y722199D01*
X88432Y722249D01*
G03Y724751I-1932J1251D01*
G01X88400Y724801D01*
Y731921D01*
X88422Y731964D01*
G03X88602Y732700I-1422J738D01*
G01Y734100D01*
G03X88422Y734836I-1602J-2D01*
G01X88400Y734879D01*
Y815900D01*
X89000Y816500D01*
X107000D01*
X110900Y812600D01*
Y792602D01*
Y792598D01*
G03Y792402I2600J-98D01*
G01Y792398D01*
Y713900D01*
X109000Y712000D01*
X91000D01*
G37*
G36*
G01X127500Y705000D02*
X126500Y706000D01*
Y714500D01*
X122318Y718682D01*
X122304Y718709D01*
G03X121209Y719804I-2304J-1209D01*
G01X121182Y719818D01*
X121000Y720000D01*
X120722D01*
X120696Y720007D01*
G03X119304I-696J-2507D01*
G01X119278Y720000D01*
X118500D01*
X115000Y723500D01*
Y726000D01*
X116000Y727000D01*
X120000D01*
X122500Y724500D01*
X132500D01*
X134000Y723000D01*
Y717500D01*
X137000Y714500D01*
X138500D01*
X138750Y714250D01*
Y705750D01*
X138000Y705000D01*
X127500D01*
G37*
G36*
G01X113049Y1407087D02*
X112462Y1406500D01*
X106500D01*
X106263Y1406737D01*
X106306Y1406856D01*
G03X106402Y1407400I-1506J546D01*
G01Y1408800D01*
G03X106045Y1409808I-1602J0D01*
G01X106000Y1409863D01*
Y1410100D01*
X105000Y1411100D01*
X103900D01*
X103300Y1411700D01*
Y1421000D01*
X103781Y1421481D01*
X103892Y1421451D01*
G03X104300Y1421398I409J1549D01*
G01X105700D01*
G03X106108Y1421451I-1J1602D01*
G01X106219Y1421481D01*
X106700Y1421000D01*
Y1416100D01*
X107600Y1415200D01*
X112500D01*
X116600Y1419300D01*
Y1421600D01*
X116937Y1421937D01*
X117038Y1421920D01*
G03X117300Y1421898I265J1580D01*
G01X118700D01*
G03X119230Y1421989I-2J1602D01*
G01X119262Y1422000D01*
X119500D01*
X120000Y1421500D01*
Y1416500D01*
X113770Y1410270D01*
X113750Y1410258D01*
G03X112998Y1408900I850J-1358D01*
G01Y1407500D01*
G03X113028Y1407192I1602J1D01*
G01X113049Y1407087D01*
G37*
G36*
G01X100112Y1381976D02*
X98976Y1383112D01*
Y1389888D01*
X99612Y1390524D01*
X111500D01*
Y1382500D01*
X111682Y1382318D01*
G02X111541Y1381976I-141J-142D01*
G01X100112D01*
G37*
G36*
G01X143598Y573729D02*
X143529Y573669D01*
G03X143444Y569808I1701J-1969D01*
G03X143221Y569515I1154J-1110D01*
G02X142642Y569395I-344J204D01*
G03X141700Y569702I-943J-1295D01*
G01X139100D01*
G03X137539Y568457I0J-1601D01*
G01X137503Y568302D01*
X136978D01*
X136921Y568351D01*
G03X135435Y568991I-1721J-1951D01*
G02X135188Y569673I36J399D01*
G01X138802Y573286D01*
Y574401D01*
X138850Y574450D01*
Y577550D01*
X139500Y578200D01*
X142990D01*
X143001Y578011D01*
G03X143532Y576907I1599J89D01*
G01X143598Y576847D01*
Y573729D01*
G37*
G36*
G01X156000Y641500D02*
X155000Y642500D01*
Y651319D01*
X155057Y651378D01*
G03Y655022I-1857J1822D01*
G01X155000Y655081D01*
Y665500D01*
X157098Y667598D01*
X161488D01*
X173161Y655925D01*
G02X173041Y655277I-283J-283D01*
G03X171525Y652527I1059J-2377D01*
G01X171539Y652427D01*
X170612Y651500D01*
X167500D01*
X164000Y648000D01*
Y641500D01*
X156000D01*
G37*
G36*
G01X158607Y697600D02*
G03X158619Y692401I-107J-2600D01*
G01X158707Y692405D01*
X159206Y691906D01*
X159201Y691818D01*
G03X163437Y690456I2299J-118D01*
G02X164019Y690555I336J-216D01*
G03X166599Y694357I1413J1818D01*
G01X166512Y694408D01*
X166500Y694420D01*
Y696901D01*
G02X166920Y697301I400J0D01*
G03X167000Y697298I100J1598D01*
G01X168400D01*
G03X169378Y697632I-1J1602D01*
G01X169432Y697673D01*
X169700D01*
Y697400D01*
X175498Y691602D01*
Y688800D01*
X173699Y687000D01*
X161199D01*
X157498Y690702D01*
X152998D01*
X152845Y690855D01*
X152884Y690972D01*
G03X150018Y693899I-2184J728D01*
G02X149500Y694281I-118J382D01*
G01Y694500D01*
X146000Y698000D01*
X141199D01*
X140000Y699199D01*
Y704901D01*
X140102Y705002D01*
Y714998D01*
X140000Y715099D01*
Y716500D01*
X139500Y717000D01*
X136500D01*
X135500Y718000D01*
Y722500D01*
X137000Y724000D01*
X144859D01*
X144904Y723976D01*
G03X147096I1096J2024D01*
G01X147141Y724000D01*
X151000D01*
X151098Y724098D01*
X152798D01*
X154752Y726052D01*
Y735252D01*
X155000Y735500D01*
X159038D01*
Y728102D01*
X159598D01*
X160000Y727700D01*
X164400D01*
X164802Y728102D01*
X165402D01*
Y735298D01*
X166702D01*
X166718Y735282D01*
Y728102D01*
X167000D01*
Y724500D01*
X165950Y723450D01*
X163250D01*
X154800Y715000D01*
X150500D01*
X149502Y714002D01*
X148800D01*
G03X147484Y713313I0J-1601D01*
G01X147424Y713226D01*
X147145D01*
X147085Y713307D01*
G03Y710193I-2085J-1557D01*
G01X147145Y710274D01*
X147368D01*
X147427Y710176D01*
G03X148800Y709398I1374J824D01*
G01X149763D01*
X150534Y708628D01*
X151000D01*
Y706594D01*
X150991Y706565D01*
G03X150891Y705968I2201J-676D01*
G01X150889Y705889D01*
X150202Y705202D01*
X149700D01*
G03X148964Y705022I2J-1602D01*
G01X148921Y705000D01*
X148500D01*
X148452Y704952D01*
X148222D01*
X148175Y704980D01*
G03X145894Y700981I-1175J-1980D01*
G01X145919Y700967D01*
X146338Y700548D01*
X149022D01*
X149060Y700532D01*
G03X149700Y700398I641J1468D01*
G01X151300D01*
G03X152411Y700847I-1J1602D01*
G02X152689I139J-144D01*
G03X153800Y700398I1112J1153D01*
G01X155200D01*
G03X156240Y700782I-1J1602D01*
G02X156760I260J-304D01*
G03X157800Y700398I1041J1218D01*
G01X159200D01*
G03X159318Y700403I-9J1602D01*
G01X159409Y700410D01*
X159615Y700203D01*
X159024Y699612D01*
Y697999D01*
G02X158607Y697600I-400J1D01*
G37*
%LPC*%
G75*
G36*
G01X144736Y1009123D02*
G02X145485Y1006060I-1636J-2023D01*
G03X145852Y1005500I367J-160D01*
G01X151335D01*
G02X151400Y1005502I82J-1599D01*
G01X152800D01*
G02X152865Y1005500I-17J-1601D01*
G01X155000D01*
X160521Y999979D01*
G02X160634Y999952I-318J-1580D01*
G01X162402D01*
X162425Y999957D01*
G02X162800Y1000002I377J-1557D01*
G01X164200D01*
G02X164575Y999957I-2J-1602D01*
G01X164598Y999952D01*
X166162D01*
X170202Y995912D01*
Y950088D01*
X163662Y943548D01*
X158098D01*
X158075Y943543D01*
G02X157700Y943498I-377J1557D01*
G01X156300D01*
G02X155925Y943543I2J1602D01*
G01X155902Y943548D01*
X154098D01*
X154075Y943543D01*
G02X153700Y943498I-377J1557D01*
G01X152300D01*
G02X151925Y943543I2J1602D01*
G01X151902Y943548D01*
X150098D01*
X150075Y943543D01*
G02X149700Y943498I-377J1557D01*
G01X148300D01*
G02X147925Y943543I2J1602D01*
G01X147902Y943548D01*
X147202D01*
Y935288D01*
X142212Y930298D01*
X130394D01*
X126588Y934104D01*
X124304D01*
X123498Y933298D01*
X115498D01*
X107702Y925502D01*
Y922674D01*
X103126Y918098D01*
X86374D01*
X77198Y927274D01*
Y927290D01*
X76790Y927698D01*
X76774D01*
X75775Y928698D01*
X41000D01*
G02Y935100I0J3201D01*
G01X78427D01*
X79426Y934102D01*
X79442D01*
X83602Y929942D01*
Y929926D01*
X89026Y924502D01*
X100474D01*
X101298Y925326D01*
Y926002D01*
X100298Y927002D01*
Y934998D01*
X100548Y935248D01*
Y936298D01*
X93502D01*
X90798Y939002D01*
Y941502D01*
X89502Y942798D01*
X84298D01*
X83000Y941500D01*
X59500D01*
X59002Y941998D01*
X58902D01*
X57298Y943602D01*
Y968702D01*
X57000Y969000D01*
X55500D01*
X54300Y970200D01*
X51500D01*
X50701Y970999D01*
X50650Y971014D01*
G02X51500Y977302I850J3087D01*
G01X53902D01*
X54000Y977400D01*
Y980000D01*
X54198Y980198D01*
Y981200D01*
G02X55800Y982802I1602J0D01*
G01X56302D01*
X57500Y984000D01*
X68563D01*
X68613Y984033D01*
G02X69500Y984302I888J-1333D01*
G01X72100D01*
G02X72987Y984033I-1J-1602D01*
G01X73037Y984000D01*
X73500D01*
Y988500D01*
X74500Y989500D01*
X75235D01*
G02X75300Y989502I82J-1599D01*
G01X77900D01*
G02X77965Y989500I-17J-1601D01*
G01X88444D01*
X88504Y989576D01*
G02X93142Y987855I2038J-1618D01*
G01X93139Y987768D01*
X95705Y985202D01*
X95800D01*
G02X97402Y983600I0J-1602D01*
G01Y982598D01*
X97500Y982500D01*
X101421D01*
X101464Y982522D01*
G02X102200Y982702I738J-1422D01*
G01X104800D01*
G02X105359Y982601I-1J-1602D01*
G01X105480Y982556D01*
X105712Y982788D01*
X105332Y983168D01*
X105288Y983183D01*
G02X104198Y984700I511J1517D01*
G01Y987300D01*
G02X104467Y988187I1602J-1D01*
G01X104500Y988237D01*
Y988563D01*
X104467Y988613D01*
G02X104198Y989500I1333J888D01*
G01Y992100D01*
G02X105800Y993702I1602J0D01*
G01X108400D01*
G02X109667Y993079I-1J-1602D01*
G01X109727Y993002D01*
X111502D01*
X113500Y995000D01*
Y995710D01*
X113389Y995765D01*
G02X112924Y996113I711J1435D01*
G03X112333Y996109I-294J-272D01*
G02X112294Y999634I-1933J1741D01*
G03X112888Y999647I291J274D01*
G02X114100Y1000202I1212J-1046D01*
G01X115500D01*
G02X115977Y1000129I-1J-1602D01*
G01X116093Y1000093D01*
X116500Y1000500D01*
Y1006000D01*
X119000Y1008500D01*
X121500D01*
X122931Y1007069D01*
X138286Y1022424D01*
X140901D01*
G03X141300Y1022808I-1J400D01*
G02X145985Y1024257I2600J-108D01*
G01X146045Y1024176D01*
X146688D01*
X150452Y1020413D01*
Y1015463D01*
X144705Y1009717D01*
G03X144736Y1009123I283J-283D01*
G37*
G36*
G01X104500Y1267000D02*
X119000D01*
X122000Y1264000D01*
Y1255000D01*
X119500Y1252500D01*
X104000D01*
X100500Y1256000D01*
Y1263000D01*
X104500Y1267000D01*
G37*
G36*
G01X12194Y1691619D02*
X12219Y1691633D01*
X14652Y1694066D01*
G03X14369Y1694748I-283J282D01*
G01X12098D01*
Y1703652D01*
X12572D01*
Y1703960D01*
X12481Y1704019D01*
G02X15009Y1708554I1419J2181D01*
G01X15136Y1708494D01*
X15377Y1708735D01*
X15224Y1708888D01*
Y1717485D01*
X16580Y1718841D01*
X16464Y1718981D01*
G02X16098Y1720000I1236J1019D01*
G01Y1721400D01*
G02X16787Y1722716I1601J0D01*
G01X16874Y1722776D01*
Y1745301D01*
X27853Y1756280D01*
X27811Y1756399D01*
G02X35001Y1757585I3488J1239D01*
G01X34999Y1757501D01*
X36700Y1755800D01*
Y1734325D01*
X36976Y1734049D01*
Y1711390D01*
X35510Y1709924D01*
X35524Y1709824D01*
G02X32576Y1706876I-2575J-373D01*
G01X32476Y1706890D01*
X31860Y1706274D01*
X26118D01*
Y1703652D01*
X30502D01*
Y1694748D01*
X27687D01*
X25902Y1692963D01*
Y1692100D01*
G02X24300Y1690498I-1602J0D01*
G01X22900D01*
G02X21900Y1690849I1J1602D01*
G02X20900Y1690498I-1001J1251D01*
G01X19500D01*
G02X18974Y1690587I1J1602D01*
G01X18942Y1690598D01*
X17412D01*
X15333Y1688519D01*
X15319Y1688494D01*
G02X12194Y1691619I-2019J1106D01*
G37*
G36*
G01X32538Y1613429D02*
X32657Y1613387D01*
X33098Y1613828D01*
Y1616085D01*
G03X32561Y1616461I-400J0D01*
G02X27675Y1620697I-1262J3480D01*
G01X27697Y1620803D01*
X23000Y1625500D01*
Y1637162D01*
X22263Y1637898D01*
X21300D01*
G02X19698Y1639500I0J1602D01*
G01Y1640900D01*
G02X19800Y1641462I1602J0D01*
G03X19401Y1642002I-374J141D01*
G02X19300Y1641998I-114J1597D01*
G01X17900D01*
G02X17374Y1642087I1J1602D01*
G01X17342Y1642098D01*
X13973D01*
X13946Y1642090D01*
G02X11662Y1645917I-646J2210D01*
G03X11377Y1646598I-284J281D01*
G01X11173D01*
X11146Y1646590D01*
G02Y1651010I-646J2210D01*
G01X11173Y1651002D01*
X13188D01*
X13998Y1651812D01*
Y1652648D01*
X12498D01*
Y1661552D01*
X16476D01*
G03X16846Y1662105I1J400D01*
G02X19623Y1665675I2404J995D01*
G01X19723Y1665661D01*
X19788Y1665726D01*
X30824D01*
X30884Y1665813D01*
G02X32200Y1666502I1316J-912D01*
G01X33600D01*
G02X35202Y1664900I0J-1602D01*
G01Y1664037D01*
X39476Y1659762D01*
Y1653524D01*
X39500Y1653500D01*
Y1636000D01*
X36000Y1632500D01*
Y1621948D01*
X36050Y1621858D01*
Y1612604D01*
X34745Y1611299D01*
X34787Y1611180D01*
G02X32538Y1613429I-3488J-1239D01*
G37*
G36*
G01X70104Y823069D02*
G03X69705Y823498I-399J29D01*
G01X52295D01*
X51094Y824699D01*
X51021Y824705D01*
G02X53495Y827179I179J2295D01*
G01X53501Y827106D01*
X53705Y826902D01*
X58717D01*
G03X59085Y827457I0J400D01*
G02X62703Y830099I2122J893D01*
G01X62759Y830052D01*
X99505D01*
X99509Y830048D01*
X100306D01*
G03X100685Y830577I1J400D01*
G02X100598Y831096I1505J519D01*
G01Y832496D01*
G02X101576Y833971I1601J0D01*
G01X101698Y834023D01*
Y836329D01*
X101634Y836389D01*
G02X100798Y838300I1766J1911D01*
G03X100384Y838700I-400J0D01*
G02X98849Y842787I-84J2300D01*
G01X98923Y842847D01*
Y845000D01*
X95106D01*
X92505Y842398D01*
X89349D01*
X89289Y842332D01*
G02X88096Y841798I-1194J1068D01*
G01X86696D01*
G02X85696Y842149I1J1602D01*
G02X84696Y841798I-1001J1251D01*
G01X83296D01*
G02X82770Y841887I1J1602D01*
G01X82738Y841898D01*
X56988D01*
X56419Y842467D01*
X56394Y842481D01*
G02X58881Y846342I1107J2019D01*
G01X58935Y846302D01*
X81744D01*
Y847402D01*
X81739Y847425D01*
G02X81694Y847800I1557J377D01*
G01Y849200D01*
G02X81739Y849575I1602J-2D01*
G01X81744Y849598D01*
Y851802D01*
X81739Y851825D01*
G02X81694Y852200I1557J377D01*
G01Y853600D01*
G02X81743Y853989I1601J-4D01*
G01X81748Y854013D01*
Y856102D01*
X81743Y856125D01*
G02X81698Y856500I1557J377D01*
G01Y857900D01*
G02X81743Y858275I1602J-2D01*
G01X81748Y858298D01*
Y860402D01*
X81743Y860425D01*
G02X81698Y860800I1557J377D01*
G01Y862200D01*
G02X81743Y862575I1602J-2D01*
G01X81748Y862598D01*
Y864602D01*
X81743Y864625D01*
G02X81698Y865000I1557J377D01*
G01Y866400D01*
G02X81743Y866775I1602J-2D01*
G01X81748Y866798D01*
Y870016D01*
X82000Y870267D01*
Y873000D01*
X85000Y876000D01*
X94500D01*
X96158Y877658D01*
X96171Y877712D01*
G02X99670Y879514I2529J-612D01*
G01X99706Y879500D01*
X100065D01*
G03X100432Y880060I0J400D01*
G02X100298Y880700I1468J641D01*
G01Y882100D01*
G02X100385Y882619I1592J0D01*
G03X100006Y883148I-378J129D01*
G01X70455D01*
X68305Y880998D01*
X66152D01*
X66096Y880951D01*
G02X62303Y882543I-1496J1749D01*
G03X61859Y882913I-399J-27D01*
G02X59306Y885390I-259J2287D01*
G03X58907Y885824I-399J34D01*
G01X58701D01*
G03X58301Y885435I0J-400D01*
G02X56451Y883243I-2301J65D01*
G03X56246Y882567I78J-393D01*
G01X56781Y882033D01*
X56806Y882019D01*
G02X53681Y878894I-1106J-2019D01*
G01X53667Y878919D01*
X52488Y880098D01*
X45448D01*
Y887488D01*
X42530Y890406D01*
X42465Y890416D01*
G02X41098Y892000I234J1584D01*
G01Y893400D01*
G02X41449Y894400I1602J-1D01*
G02X41327Y894576I1252J998D01*
G01X41268Y894674D01*
X38454D01*
X32657Y900471D01*
X32538Y900429D01*
G02X34787Y902678I-1239J3488D01*
G01X34745Y902559D01*
X39678Y897626D01*
X41324D01*
X41384Y897713D01*
G02X42700Y898402I1316J-912D01*
G01X44100D01*
Y898401D01*
G03X44500Y898801I0J400D01*
G01Y902500D01*
X58500Y916500D01*
Y917512D01*
X57988Y918024D01*
X48032D01*
G03X47646Y917519I0J-400D01*
G02X47702Y917100I-1546J-420D01*
G01Y915700D01*
G02X46100Y914098I-1602J0D01*
G01X44700D01*
G02X43354Y914832I0J1601D01*
G01X43295Y914924D01*
X35356D01*
G03X34960Y914464I0J-400D01*
G02X32538Y917405I-3661J-547D01*
G01X32657Y917363D01*
X33170Y917876D01*
X34286D01*
G03X34569Y918559I0J400D01*
G01X32657Y920471D01*
X32538Y920429D01*
G02X34787Y922678I-1239J3488D01*
G01X34745Y922559D01*
X36328Y920976D01*
X59212D01*
X65117Y915071D01*
X65172Y915058D01*
G02X66402Y913500I-372J-1558D01*
G01Y912687D01*
X76027Y903061D01*
X76127Y903075D01*
G02X79025Y901128I373J-2575D01*
G01X79063Y900976D01*
X145243D01*
X145284Y901122D01*
G02X149594Y899543I2216J-622D01*
G03X149957Y898976I364J-167D01*
G01X155712D01*
X155768Y899082D01*
G02X156665Y895997I2032J-1082D01*
G01X156619Y896024D01*
X73112D01*
X68872Y891784D01*
G03X69155Y891102I283J-282D01*
G01X111405D01*
X115955Y886552D01*
X117389D01*
X117448Y886613D01*
G02X118600Y887102I1152J-1112D01*
G01X120000D01*
G02X121602Y885500I0J-1602D01*
G01Y884100D01*
G02X121251Y883100I-1602J1D01*
G02X121602Y882100I-1251J-1001D01*
G01Y880700D01*
G02X120000Y879098I-1602J0D01*
G01X119884D01*
G03X119743Y878757I0J-200D01*
G01X120500Y878000D01*
Y855000D01*
X115522Y850022D01*
Y842102D01*
X115322D01*
Y840885D01*
X117409Y838797D01*
X117550Y838926D01*
G02X121344Y835390I1750J-1926D01*
G01X121302Y835336D01*
Y833753D01*
X121368Y833693D01*
G02X121902Y832500I-1068J-1194D01*
G01Y831100D01*
G02X121551Y830100I-1602J1D01*
G02X121902Y829100I-1251J-1001D01*
G01Y827700D01*
G02X120300Y826098I-1602J0D01*
G01X119305D01*
X117201Y823994D01*
X117195Y823921D01*
G02X114721Y826395I-2295J179D01*
G01X114794Y826401D01*
X117299Y828905D01*
X117298Y829100D01*
G02X117649Y830100I1602J-1D01*
G02X117298Y831100I1251J1001D01*
G01Y832500D01*
G02X117421Y833115I1602J-1D01*
G03X117276Y833599I-369J153D01*
G02X117220Y833645I225J331D01*
G03X116100Y834102I-1120J-1144D01*
G01X114700D01*
G03X113580Y833645I0J-1601D01*
G02X113524Y833599I-281J285D01*
G03X113379Y833115I224J-331D01*
G02X113502Y832500I-1479J-616D01*
G01Y831100D01*
G02X113151Y830100I-1602J1D01*
G02X113502Y829100I-1251J-1001D01*
G01Y827700D01*
G02X112010Y826102I-1602J0D01*
G03X111824Y825903I14J-199D01*
G01Y825212D01*
X111088Y824476D01*
X109732D01*
X108755Y823498D01*
X101595D01*
G03X101196Y823069I0J-400D01*
G02X97191Y821358I-2296J-169D01*
G01X97132Y821424D01*
X74168D01*
X74109Y821358D01*
G02X70104Y823069I-1709J1542D01*
G37*
G36*
G01X28664Y213467D02*
X28804Y213608D01*
X22274Y220138D01*
Y235362D01*
X26424Y239512D01*
Y242448D01*
X24198D01*
Y251602D01*
X20894D01*
Y258504D01*
X25961D01*
X26021Y258579D01*
G02X26183Y258762I2027J-1631D01*
G01X26239Y258820D01*
Y259102D01*
X24770D01*
Y266004D01*
X25994D01*
Y267698D01*
X25945Y267754D01*
G02X26126Y271375I1955J1717D01*
G03X26136Y271950I-273J292D01*
G01X25369Y272717D01*
X25344Y272731D01*
G02X28469Y275856I1106J2019D01*
G01X28483Y275831D01*
X29812Y274502D01*
X31542D01*
X31574Y274513D01*
G02X32100Y274602I527J-1513D01*
G01X33500D01*
G02X34500Y274251I-1J-1602D01*
G02X35500Y274602I1001J-1251D01*
G01X36900D01*
G02X38246Y273868I0J-1601D01*
G01X38305Y273776D01*
X41632D01*
X41691Y273842D01*
G02X45173Y270832I1709J-1542D01*
G03X45481Y270176I308J-256D01*
G01X47388D01*
X51888Y274676D01*
X51843Y274796D01*
G02X54884Y273474I2157J804D01*
G01X54847Y273459D01*
X48612Y267224D01*
X41227D01*
X40187Y266184D01*
G03X40470Y265502I283J-282D01*
G01X42036D01*
X46176Y261361D01*
Y250498D01*
G03X46861Y250217I400J0D01*
G02X50609Y247678I1639J-1617D01*
G03X50805Y247399I184J-79D01*
G02X50900Y247402I98J-1599D01*
G01X53500D01*
G02X55102Y245800I0J-1602D01*
G01Y243200D01*
G02X53500Y241598I-1602J0D01*
G01X50900D01*
G02X49850Y241991I1J1602D01*
G02X48798Y241598I-1051J1208D01*
G01X46198D01*
G02X45101Y242032I-1J1601D01*
G03X44544Y242023I-274J-291D01*
G01X34745Y232224D01*
X34787Y232105D01*
G02X32538Y234354I-3488J-1239D01*
G01X32657Y234312D01*
X40111Y241766D01*
G03X39828Y242449I-283J283D01*
G01X34976D01*
Y241088D01*
X26976Y233088D01*
Y224812D01*
X28493Y223295D01*
X28636Y223437D01*
X28637Y223439D01*
G02X30356Y217286I2662J-2573D01*
G03X29972Y216616I-101J-387D01*
G01X32109Y214479D01*
X32164Y214465D01*
G02X28664Y213467I-866J-3599D01*
G37*
G36*
G01X19576Y49707D02*
X19628Y49586D01*
X55497D01*
X61637Y55726D01*
G03X61354Y56408I-283J282D01*
G01X19530D01*
X19475Y56299D01*
G02Y59921I-3569J1811D01*
G01X19530Y59812D01*
X62610D01*
X63349Y60550D01*
G03X63130Y61228I-283J283D01*
G02X62217Y65411I370J2272D01*
G03X62291Y66011I-223J332D01*
G02X64646Y69763I1709J1542D01*
G01X64673Y69754D01*
X64702D01*
G03X65101Y70184I0J400D01*
G02X65096Y70303I1597J127D01*
G01Y71266D01*
X61339Y75024D01*
X50655D01*
G03X50469Y74269I-1J-400D01*
G02X44019I-3225J-6159D01*
G03X43833Y75024I-185J355D01*
G01X42412D01*
X34022Y66634D01*
X19628D01*
X19576Y66513D01*
G02X14229Y71744I-3670J1597D01*
G03X14278Y72075I-84J182D01*
G02X14114Y72235I1628J1833D01*
G01X14055Y72298D01*
X10002D01*
X7798Y74502D01*
Y81998D01*
X10502Y84702D01*
X12693D01*
G03X12985Y85375I0J400D01*
G02X18323Y84920I2922J2735D01*
G03X18565Y84202I242J-318D01*
G01X27502D01*
X51552Y108252D01*
X51602D01*
X60252Y116902D01*
X73198D01*
X73398Y116701D01*
X73627Y116930D01*
X73588Y117047D01*
G02X88055Y117883I7121J2362D01*
G03X88446Y117402I391J-81D01*
G01X108998D01*
X120802Y105598D01*
Y59502D01*
X106698Y45398D01*
X85902D01*
X82198Y49102D01*
Y51550D01*
X74002D01*
Y54013D01*
G03X73402Y54359I-400J0D01*
G02X72602Y54146I-798J1389D01*
G01X71002D01*
G02X70544Y54213I0J1601D01*
G03X70288Y53997I-57J-192D01*
G02X70300Y53803I-1590J-196D01*
G01Y52403D01*
G02X68933Y50819I-1601J0D01*
G01X68868Y50809D01*
X68857Y50798D01*
X65173D01*
X65146Y50790D01*
G02X62552Y51774I-645J2210D01*
G03X61931Y51843I-338J-214D01*
G01X56721Y46634D01*
X19628D01*
X19576Y46513D01*
G02Y49707I-3670J1597D01*
G37*
G54D111*
X177102Y1129800D03*
X171502Y1129547D03*
X178644Y1202519D03*
X163344Y1181200D03*
X183500Y1241500D03*
X165000Y1264500D03*
X164500Y1299500D03*
X191800Y1280900D03*
X141300Y298100D03*
G54D107*
X15906Y481339D03*
Y491339D03*
Y521339D03*
Y771181D03*
Y1217323D03*
Y1477165D03*
Y1910394D03*
G54D109*
X179606Y161889D03*
Y171889D03*
X169606Y161889D03*
Y171889D03*
X159606Y161889D03*
Y171889D03*
X149606Y161889D03*
Y171889D03*
X179606Y181889D03*
Y191889D03*
X169606Y181889D03*
Y191889D03*
X159606Y181889D03*
Y191889D03*
X149606Y181889D03*
Y191889D03*
X80709Y266929D03*
Y276929D03*
Y286929D03*
X110709Y266929D03*
X100709D03*
X90709D03*
X110709Y276929D03*
Y286929D03*
X100709Y276929D03*
Y286929D03*
X90709Y276929D03*
Y286929D03*
X179606Y256929D03*
Y266929D03*
X169606Y256929D03*
Y266929D03*
X159606Y256929D03*
Y266929D03*
X149606Y256929D03*
Y266929D03*
X179606Y276929D03*
Y286929D03*
X169606Y276929D03*
Y286929D03*
X159606Y276929D03*
Y286929D03*
X149606Y276929D03*
Y286929D03*
G54D108*
X150000Y64500D03*
X152500Y1906000D03*
G54D105*
X149606Y119409D03*
X80709Y329409D03*
X149606D03*
G54D103*
X80709Y139409D03*
X149606D03*
X80709Y309409D03*
X149606D03*
G54D106*
X27559Y157480D03*
Y1811023D03*
X179134Y78740D03*
X179133Y570866D03*
X179134Y1889764D03*
Y1161417D03*
G54D104*
X47244Y1207323D03*
Y1467165D03*
Y501338D03*
G54D102*
X29921Y24803D03*
Y111417D03*
Y717874D03*
Y804488D03*
X30000Y1164000D03*
X29921Y1250630D03*
Y1510472D03*
Y1857086D03*
Y1943701D03*
G54D110*
X161417Y1747835D03*
Y1823031D03*
X178937Y1328740D03*
X96457Y1747835D03*
Y1823031D03*
%LPD*%
G75*
G36*
G01X10500Y73500D02*
X9000Y75000D01*
Y81500D01*
X11000Y83500D01*
X13000D01*
X13500Y83000D01*
X28000D01*
X52050Y107050D01*
X52100D01*
X60750Y115700D01*
X72700D01*
X78850Y109550D01*
X81550D01*
X82048Y109052D01*
Y107452D01*
X80298D01*
Y98548D01*
X82048D01*
Y81048D01*
X76000Y75000D01*
X68150D01*
X63500Y79650D01*
X39950D01*
X33800Y73500D01*
X10500D01*
G37*
G36*
G01X76570Y57974D02*
X74081D01*
X74025Y58082D01*
G03X72964Y58907I-1423J-735D01*
G02X72669Y59405I90J390D01*
G03X72664Y60677I-2215J627D01*
G01X72656Y60704D01*
Y61804D01*
X72694Y61856D01*
G03X73002Y62800I-1293J944D01*
G01Y64200D01*
G03X71400Y65802I-1602J0D01*
G01X70000D01*
G03X69978Y65801I62J-1599D01*
G02X69598Y66342I-6J400D01*
G03X69700Y66903I-1500J562D01*
G01Y68303D01*
G03X69349Y69303I-1602J-1D01*
G03X69491Y69513I-1252J999D01*
G02X69769Y69585I174J-99D01*
G03X70600Y69352I832J1369D01*
G01X72200D01*
G03X72781Y69462I-2J1602D01*
G02X73026Y69378I73J-186D01*
G03X74400Y68598I1375J822D01*
G01X76313D01*
X77888Y67024D01*
X85796D01*
G02X86159Y66457I-1J-400D01*
G03X86076Y64752I2094J-956D01*
G02X85588Y64238I-378J-129D01*
G03X85147Y64300I-441J-1540D01*
G01X82547D01*
G03X81347Y63758I1J-1602D01*
G02X80747I-300J265D01*
G03X79547Y64300I-1201J-1060D01*
G01X76947D01*
G03X75346Y62698I0J-1601D01*
G01Y60098D01*
G03X76435Y58581I1601J0D01*
G01X76570Y58535D01*
Y57974D01*
G37*
G36*
G01X81904Y53769D02*
Y57454D01*
X79524D01*
Y58497D01*
G03X80747Y59038I23J1601D01*
G02X81347I300J-265D01*
G03X82547Y58496I1201J1060D01*
G01X85147D01*
G03X86550Y59325I0J1602D01*
G02X86822Y59404I175J-96D01*
G03X87603Y59200I782J1398D01*
G01X89003D01*
G03X90604Y60802I0J1601D01*
G01Y62202D01*
G03X90037Y63425I-1601J1D01*
G02X89993Y63993I258J306D01*
G03X90347Y66457I-1740J1507D01*
G02X90710Y67024I364J167D01*
G01X91898D01*
Y65548D01*
X93698D01*
Y57702D01*
X86802D01*
X82587Y53486D01*
G02X81904Y53769I-283J283D01*
G37*
G36*
G01X40013Y254727D02*
G02X39365Y254848I-282J283D01*
G03X37900Y255802I-1465J-648D01*
G01X36500D01*
G03X35122Y255016I0J-1601D01*
G02X34778I-172J102D01*
G03X34651Y255200I-1378J-816D01*
G03X35002Y256200I-1251J1001D01*
G01Y257600D01*
G03X33400Y259202I-1602J0D01*
G01X32000D01*
G03X31625Y259157I2J-1602D01*
G01X31602Y259152D01*
X30172D01*
Y262096D01*
G02X30854Y262380I400J0D01*
G03X31982Y261916I1127J1137D01*
G01X33382D01*
G03X34382Y262266I1J1601D01*
G03X35382Y261916I999J1251D01*
G01X36782D01*
G03X38001Y262478I1J1601D01*
G01X38061Y262548D01*
X40812D01*
X43224Y260137D01*
Y256783D01*
G02X42776Y256385I-400J-1D01*
G03X40481Y255206I-276J-2285D01*
G01X40467Y255181D01*
X40013Y254727D01*
G37*
G36*
G01X59400Y943200D02*
X58500Y944100D01*
Y969500D01*
X58798Y969798D01*
X70498D01*
X74399Y973700D01*
X79400D01*
X79550Y973550D01*
Y967404D01*
X79544Y967380D01*
G03X79498Y967000I1556J-381D01*
G01Y965398D01*
X72800Y958700D01*
Y944900D01*
X71100Y943200D01*
X59400D01*
G37*
G36*
G01X55500Y971000D02*
X55000Y971500D01*
Y975500D01*
X55357Y975857D01*
X55464Y975834D01*
G03X55800Y975798I338J1566D01*
G01X58400D01*
G03X59999Y977311I0J1601D01*
G01X60010Y977500D01*
X68500D01*
X69000Y978000D01*
X74198D01*
Y977698D01*
X79302D01*
X79500Y977500D01*
Y975000D01*
X74000D01*
X70000Y971000D01*
X68679D01*
X68623Y971050D01*
G03X65177I-1723J-1950D01*
G01X65121Y971000D01*
X55500D01*
G37*
G36*
G01X119600Y60000D02*
X106633Y47033D01*
X106495Y47129D01*
G03X103006Y46672I-1496J-2129D01*
G01X102946Y46600D01*
X97054D01*
X96994Y46672D01*
G03X93006I-1994J-1672D01*
G01X92946Y46600D01*
X87054D01*
X86994Y46672D01*
G03X85494Y47555I-1994J-1672D01*
G01X85434Y47566D01*
X83400Y49600D01*
Y52600D01*
X85069Y54269D01*
X85119Y54283D01*
G03X86717Y55881I-619J2217D01*
G01X86731Y55931D01*
X87300Y56500D01*
X94400D01*
X94900Y57000D01*
Y65548D01*
X99802D01*
Y71452D01*
X94900D01*
Y75500D01*
X84000D01*
X83794Y75706D01*
X83786Y75775D01*
G03X83524Y76596I-2285J-277D01*
G01X83500Y76641D01*
Y78000D01*
X83250Y78250D01*
Y112349D01*
X83379Y112398D01*
G03X87437Y116089I-2670J7011D01*
G01X87492Y116200D01*
X108500D01*
X119600Y105100D01*
Y60000D01*
G37*
G36*
G01X88065Y70461D02*
G03X88102Y70800I-1565J342D01*
G01Y72200D01*
G03X86500Y73802I-1602J0D01*
G01X85100D01*
G03X84386Y73634I0J-1601D01*
G02X83887Y73754I-178J358D01*
G03X83710Y73954I-1284J-958D01*
G01X83649Y74013D01*
Y74298D01*
X93698D01*
Y71452D01*
X91898D01*
Y69976D01*
X88456D01*
G02X88065Y70461I0J400D01*
G37*
G36*
G01X104000Y925000D02*
X101500Y927500D01*
Y934500D01*
X102000Y935000D01*
X107000D01*
X107198Y935198D01*
X108452D01*
Y936452D01*
X109437Y937437D01*
X109538Y937420D01*
G03X109800Y937398I265J1580D01*
G01X111200D01*
G03X112676Y938378I0J1602D01*
G01X112727Y938500D01*
X115073D01*
X115124Y938378D01*
G03X116600Y937398I1476J622D01*
G01X118000D01*
G03X119209Y937950I-1J1602D01*
G02X119803Y937961I302J-263D01*
G03X120971Y937454I1169J1095D01*
G01X122371D01*
G03X123143Y937653I-1J1602D01*
G01X123275Y937725D01*
X123500Y937500D01*
Y935000D01*
X123000Y934500D01*
X115000D01*
X105500Y925000D01*
X104000D01*
G37*
G36*
G01X132218Y934702D02*
X128412Y938508D01*
X124192D01*
X123947Y938753D01*
X123959Y938850D01*
G03X123972Y939056I-1588J204D01*
G01Y940456D01*
G03X122371Y942058I-1602J0D01*
G01X121530D01*
Y943455D01*
X121611Y943515D01*
G03Y947685I-1557J2085D01*
G01X121530Y947745D01*
Y952708D01*
X122265Y953442D01*
X123229D01*
G03X124830Y955044I0J1601D01*
G01Y956444D01*
G03X123229Y958046I-1602J0D01*
G01X122366D01*
X120982Y959429D01*
Y967202D01*
X112058D01*
Y958798D01*
X112484D01*
Y958046D01*
X111829D01*
G03X110513Y957357I0J-1601D01*
G01X110453Y957270D01*
X109882D01*
X108673Y956061D01*
X108573Y956075D01*
G03X105625Y953127I-373J-2575D01*
G01X105639Y953027D01*
X104574Y951962D01*
Y946202D01*
X99498D01*
X97702Y947998D01*
Y955795D01*
X105202Y963295D01*
Y964529D01*
X105266Y964589D01*
G03Y968411I-1766J1911D01*
G01X105202Y968471D01*
Y971343D01*
X105335Y971390D01*
G03X106402Y972900I-535J1510D01*
G01Y975500D01*
G03X105860Y976700I-1602J-1D01*
G02Y977300I265J300D01*
G03X106402Y978500I-1060J1201D01*
G01Y981100D01*
G03X106401Y981127I-1600J-46D01*
G02X107084Y981416I400J6D01*
G01X110000Y978500D01*
Y977500D01*
X110500Y977000D01*
X123933D01*
X124298Y976634D01*
Y973088D01*
X128086Y969300D01*
X162914D01*
X165116Y971502D01*
G02X165798Y971219I282J-283D01*
G01Y951912D01*
X161838Y947952D01*
X159696D01*
G02X159297Y948381I0J400D01*
G03X159302Y948500I-1597J127D01*
G01Y949900D01*
G03X157700Y951502I-1602J0D01*
G01X156837D01*
X154776Y953562D01*
X154762Y953587D01*
G03X154246Y954221I-2015J-1113D01*
G01X154176Y954281D01*
Y955298D01*
X154602D01*
Y963702D01*
X135438D01*
Y960976D01*
X131388D01*
X131179Y960767D01*
X131088Y960773D01*
G03X128508Y957162I-185J-2595D01*
G01X128524Y957124D01*
Y950388D01*
X129485Y949427D01*
X129409Y949294D01*
G03X129198Y948500I1391J-795D01*
G01Y947100D01*
G03X130800Y945498I1602J0D01*
G01X132200D01*
G03X133440Y946087I-1J1602D01*
G02X134060I310J-253D01*
G03X135300Y945498I1241J1013D01*
G01X136700D01*
G03X137940Y946087I-1J1602D01*
G02X138560I310J-253D01*
G03X139800Y945498I1241J1013D01*
G01X141200D01*
G03X142079Y945761I0J1602D01*
G02X142698Y945427I219J-334D01*
G01Y945100D01*
G03X142787Y944574I1602J1D01*
G01X142798Y944542D01*
Y937112D01*
X140388Y934702D01*
X132218D01*
G37*
G36*
G01X94000Y937500D02*
X92000Y939500D01*
Y942000D01*
X90000Y944000D01*
X84500D01*
X83500Y945000D01*
Y954000D01*
X88500Y959000D01*
X95500D01*
X96500Y958000D01*
Y953722D01*
X96493Y953696D01*
G03Y952304I2507J-696D01*
G01X96500Y952278D01*
Y947500D01*
X99000Y945000D01*
X105912D01*
X108000Y942912D01*
Y938500D01*
X107302Y937802D01*
X100548D01*
Y937500D01*
X94000D01*
G37*
G36*
G01X93000Y970500D02*
X92500Y971000D01*
Y974500D01*
X92000Y975000D01*
X85000D01*
Y974902D01*
X84798D01*
Y971298D01*
X84500Y971000D01*
X82500D01*
X82000Y971500D01*
Y980500D01*
X82500Y981000D01*
X84500D01*
X84798Y980702D01*
Y977698D01*
X85802D01*
X86000Y977500D01*
X91000D01*
X91198Y977698D01*
X91202D01*
Y977702D01*
X92000Y978500D01*
X96094D01*
X96545Y978048D01*
X96911D01*
Y977798D01*
X96887Y977754D01*
G03X96698Y977000I1413J-755D01*
G01Y975600D01*
G03X96967Y974713I1602J1D01*
G01X97000Y974663D01*
Y971000D01*
X96500Y970500D01*
X93000D01*
G37*
G36*
G01X129112Y976798D02*
X130812Y978498D01*
X132100D01*
G03X133638Y979654I0J1601D01*
G01X133680Y979798D01*
X135000D01*
Y977500D01*
X135500Y977000D01*
X147800D01*
G02X148200Y976585I0J-400D01*
G03X149856Y974290I2300J-85D01*
G01X150000Y974248D01*
Y973704D01*
X129910D01*
X128702Y974912D01*
Y976798D01*
X129112D01*
G37*
G36*
G01X125958Y981202D02*
X125622Y981538D01*
X123542D01*
Y989402D01*
X123116D01*
Y995578D01*
X123137Y995598D01*
X124000D01*
G03X125064Y996003I-1J1602D01*
G02X125613Y995987I266J-299D01*
G01X126000Y995600D01*
X134998D01*
Y992013D01*
X135000Y992012D01*
Y983402D01*
X133544D01*
X133487Y983501D01*
G03X132635Y984210I-1387J-801D01*
G01X132502Y984257D01*
Y984665D01*
X132535Y984715D01*
G03X132802Y985600I-1335J885D01*
G01Y988200D01*
G03X131200Y989802I-1602J0D01*
G01X128600D01*
G03X126998Y988200I0J-1602D01*
G01Y985600D01*
G03X127963Y984130I1602J0D01*
G02X128143Y983551I-159J-367D01*
G03X127898Y982700I1357J-851D01*
G01Y981812D01*
X127288Y981202D01*
X125958D01*
G37*
G36*
G01X165798Y978412D02*
X161090Y973704D01*
X157673D01*
G02X157277Y974162I0J400D01*
G03X157024Y975596I-2277J338D01*
G01X157000Y975641D01*
Y977498D01*
X157162D01*
Y986074D01*
X163087Y991998D01*
X164200D01*
G03X165159Y992317I0J1601D01*
G02X165798Y991997I239J-320D01*
G01Y978412D01*
G37*
%LPC*%
G75*
G54D111*
X105000Y55000D03*
G54D107*
X15906Y78110D03*
%LPD*%
G75*
G54D100*
G01X-430254Y-152763D02*
Y-135263D01*
G01X-421958D02*
X-430254Y-146055D01*
G01X-420648Y-152763D02*
X-426543Y-141097D01*
G01X-412973Y-152763D02*
Y-135263D01*
X-402929Y-152763D01*
Y-135263D01*
G01X-390451Y-152763D02*
X-392198Y-152471D01*
X-393726Y-151305D01*
X-395036Y-149555D01*
X-395910Y-147513D01*
X-396346Y-145180D01*
Y-142846D01*
X-395910Y-140513D01*
X-395036Y-138471D01*
X-393726Y-136722D01*
X-392198Y-135555D01*
X-390451Y-135263D01*
X-388705Y-135555D01*
X-387176Y-136722D01*
X-385866Y-138471D01*
X-384992Y-140513D01*
X-384556Y-142846D01*
Y-145180D01*
X-384992Y-147513D01*
X-385866Y-149555D01*
X-387176Y-151305D01*
X-388705Y-152471D01*
X-390451Y-152763D01*
G01X-377536D02*
X-368366Y-135263D01*
G01X-377536D02*
X-368366Y-152763D01*
G01X-362001Y-158596D02*
X-348901D01*
G01X-342099Y-152763D02*
Y-135263D01*
X-333803D01*
G01X-336859Y-143721D02*
X-342099D01*
G01X-325910Y-152763D02*
X-320451Y-135263D01*
X-314992Y-152763D01*
G01X-316958Y-146638D02*
X-323945D01*
G01X-307973Y-152763D02*
Y-135263D01*
X-297929Y-152763D01*
Y-135263D01*
G01X-263148Y-136722D02*
X-264458Y-135846D01*
X-265986Y-135263D01*
X-267733D01*
X-269698Y-136138D01*
X-271226Y-137596D01*
X-272318Y-139347D01*
X-273191Y-142263D01*
X-273410Y-144888D01*
X-272973Y-147513D01*
X-272318Y-149263D01*
X-271008Y-151013D01*
X-269479Y-152180D01*
X-267951Y-152763D01*
X-266423D01*
X-264894Y-152180D01*
X-263584Y-151305D01*
X-262492Y-150139D01*
G01X-250451Y-152763D02*
X-252198Y-152471D01*
X-253726Y-151305D01*
X-255036Y-149555D01*
X-255910Y-147513D01*
X-256346Y-145180D01*
Y-142846D01*
X-255910Y-140513D01*
X-255036Y-138471D01*
X-253726Y-136722D01*
X-252198Y-135555D01*
X-250451Y-135263D01*
X-248705Y-135555D01*
X-247176Y-136722D01*
X-245866Y-138471D01*
X-244992Y-140513D01*
X-244556Y-142846D01*
Y-145180D01*
X-244992Y-147513D01*
X-245866Y-149555D01*
X-247176Y-151305D01*
X-248705Y-152471D01*
X-250451Y-152763D01*
G01X-237973D02*
Y-135263D01*
X-227929Y-152763D01*
Y-135263D01*
G01X-215451D02*
Y-152763D01*
G01X-220473Y-135263D02*
X-210429D01*
G01X-202318Y-152763D02*
Y-135263D01*
X-196859D01*
X-195113Y-136138D01*
X-194021Y-137305D01*
X-193584Y-139638D01*
X-194021Y-141972D01*
X-195331Y-143430D01*
X-196859Y-144305D01*
X-202318D01*
G01X-196859D02*
X-193584Y-152763D01*
G01X-180451D02*
X-182198Y-152471D01*
X-183726Y-151305D01*
X-185036Y-149555D01*
X-185910Y-147513D01*
X-186346Y-145180D01*
Y-142846D01*
X-185910Y-140513D01*
X-185036Y-138471D01*
X-183726Y-136722D01*
X-182198Y-135555D01*
X-180451Y-135263D01*
X-178705Y-135555D01*
X-177176Y-136722D01*
X-175866Y-138471D01*
X-174992Y-140513D01*
X-174556Y-142846D01*
Y-145180D01*
X-174992Y-147513D01*
X-175866Y-149555D01*
X-177176Y-151305D01*
X-178705Y-152471D01*
X-180451Y-152763D01*
G01X-167318Y-135263D02*
Y-152763D01*
X-158584D01*
G01X-126205Y-143430D02*
X-125331Y-142555D01*
X-124676Y-141097D01*
X-124239Y-139054D01*
X-124676Y-137305D01*
X-125549Y-136138D01*
X-127078Y-135263D01*
X-132973D01*
Y-152763D01*
X-125768D01*
X-124239Y-151597D01*
X-123366Y-149846D01*
X-122929Y-147805D01*
X-123366Y-145763D01*
X-124676Y-144013D01*
X-126205Y-143430D01*
X-132973D01*
G01X-110451Y-152763D02*
X-112198Y-152471D01*
X-113726Y-151305D01*
X-115036Y-149555D01*
X-115910Y-147513D01*
X-116346Y-145180D01*
Y-142846D01*
X-115910Y-140513D01*
X-115036Y-138471D01*
X-113726Y-136722D01*
X-112198Y-135555D01*
X-110451Y-135263D01*
X-108705Y-135555D01*
X-107176Y-136722D01*
X-105866Y-138471D01*
X-104992Y-140513D01*
X-104556Y-142846D01*
Y-145180D01*
X-104992Y-147513D01*
X-105866Y-149555D01*
X-107176Y-151305D01*
X-108705Y-152471D01*
X-110451Y-152763D01*
G01X-98410D02*
X-92951Y-135263D01*
X-87492Y-152763D01*
G01X-89458Y-146638D02*
X-96445D01*
G01X-79818Y-152763D02*
Y-135263D01*
X-74359D01*
X-72613Y-136138D01*
X-71521Y-137305D01*
X-71084Y-139638D01*
X-71521Y-141972D01*
X-72831Y-143430D01*
X-74359Y-144305D01*
X-79818D01*
G01X-74359D02*
X-71084Y-152763D01*
G01X-62754D02*
Y-135263D01*
X-58388D01*
X-56641Y-136138D01*
X-55331Y-137305D01*
X-54239Y-139054D01*
X-53366Y-141097D01*
X-53148Y-144013D01*
X-53366Y-146930D01*
X-54239Y-148972D01*
X-55331Y-150722D01*
X-56641Y-151888D01*
X-58388Y-152763D01*
X-62754D01*
G01X-282378Y-107763D02*
Y-90263D01*
X-276701Y-104846D01*
X-271024Y-90263D01*
Y-107763D01*
G01X-259201D02*
X-260511Y-107471D01*
X-261821Y-106305D01*
X-262695Y-104263D01*
X-263131Y-101930D01*
X-262695Y-99596D01*
X-261821Y-97555D01*
X-260511Y-96388D01*
X-259201Y-96097D01*
X-257891Y-96388D01*
X-256581Y-97555D01*
X-255708Y-99596D01*
X-255489Y-101930D01*
X-255708Y-104263D01*
X-256581Y-106305D01*
X-257891Y-107471D01*
X-259201Y-107763D01*
G01X-237771Y-90263D02*
Y-107763D01*
G01Y-105139D02*
X-238644Y-106597D01*
X-239955Y-107471D01*
X-241483Y-107763D01*
X-243229Y-107180D01*
X-244539Y-105722D01*
X-245413Y-103972D01*
X-245631Y-101930D01*
X-245413Y-99888D01*
X-244539Y-98138D01*
X-243229Y-96680D01*
X-241483Y-96097D01*
X-239955Y-96388D01*
X-238863Y-96972D01*
X-237771Y-98138D01*
G01X-227476Y-99888D02*
X-220489D01*
X-221144Y-97846D01*
X-222236Y-96680D01*
X-223764Y-96097D01*
X-225293Y-96388D01*
X-226603Y-97263D01*
X-227476Y-99305D01*
X-227913Y-101055D01*
Y-102805D01*
X-227476Y-104555D01*
X-226384Y-106305D01*
X-225074Y-107471D01*
X-223546Y-107763D01*
X-222018Y-107180D01*
X-220489Y-105430D01*
G01X-206701Y-107763D02*
Y-90263D01*
G01X-901Y-152763D02*
Y-135263D01*
X-3521Y-138763D01*
G01Y-152763D02*
X1719D01*
G01X12451Y-138180D02*
X13761Y-136430D01*
X15289Y-135555D01*
X17036Y-135263D01*
X19219Y-135846D01*
X20747Y-137305D01*
X21184Y-139054D01*
X20966Y-140805D01*
X20092Y-142263D01*
X15726Y-145180D01*
X13761Y-147221D01*
X12451Y-150139D01*
X12014Y-152763D01*
X21184D01*
G01X36719D02*
Y-135263D01*
X28640Y-147805D01*
X39558D01*
G01X46796Y-149263D02*
X48105Y-151305D01*
X49852Y-152471D01*
X51817Y-152763D01*
X53564Y-152471D01*
X55311Y-151013D01*
X56402Y-149263D01*
X56621Y-147513D01*
X56184Y-145472D01*
X54656Y-144013D01*
X53127Y-143430D01*
X51162D01*
G01X53127D02*
X54437Y-142555D01*
X55529Y-141097D01*
X55966Y-139347D01*
X55529Y-137596D01*
X54437Y-136138D01*
X52472Y-135263D01*
X50507Y-135555D01*
X48542Y-136722D01*
G01X64296Y-149263D02*
X65605Y-151305D01*
X67352Y-152471D01*
X69317Y-152763D01*
X71064Y-152471D01*
X72811Y-151013D01*
X73902Y-149263D01*
X74121Y-147513D01*
X73684Y-145472D01*
X72156Y-144013D01*
X70627Y-143430D01*
X68662D01*
G01X70627D02*
X71937Y-142555D01*
X73029Y-141097D01*
X73466Y-139347D01*
X73029Y-137596D01*
X71937Y-136138D01*
X69972Y-135263D01*
X68007Y-135555D01*
X66042Y-136722D01*
G01X-14018Y-107763D02*
Y-90263D01*
X-8778D01*
X-7031Y-91138D01*
X-5721Y-93180D01*
X-5284Y-95513D01*
X-5721Y-97846D01*
X-6813Y-99596D01*
X-8778Y-100472D01*
X-14018D01*
G01X12652Y-91722D02*
X11342Y-90846D01*
X9814Y-90263D01*
X8067D01*
X6102Y-91138D01*
X4574Y-92596D01*
X3482Y-94347D01*
X2609Y-97263D01*
X2390Y-99888D01*
X2827Y-102513D01*
X3482Y-104263D01*
X4792Y-106013D01*
X6321Y-107180D01*
X7849Y-107763D01*
X9377D01*
X10906Y-107180D01*
X12216Y-106305D01*
X13308Y-105139D01*
G01X27095Y-98430D02*
X27969Y-97555D01*
X28624Y-96097D01*
X29061Y-94054D01*
X28624Y-92305D01*
X27751Y-91138D01*
X26222Y-90263D01*
X20327D01*
Y-107763D01*
X27532D01*
X29061Y-106597D01*
X29934Y-104846D01*
X30371Y-102805D01*
X29934Y-100763D01*
X28624Y-99013D01*
X27095Y-98430D01*
X20327D01*
G01X36299Y-113596D02*
X49399D01*
G01X55327Y-107763D02*
Y-90263D01*
X65371Y-107763D01*
Y-90263D01*
G01X77849Y-107763D02*
X76102Y-107471D01*
X74574Y-106305D01*
X73264Y-104555D01*
X72390Y-102513D01*
X71954Y-100180D01*
Y-97846D01*
X72390Y-95513D01*
X73264Y-93471D01*
X74574Y-91722D01*
X76102Y-90555D01*
X77849Y-90263D01*
X79595Y-90555D01*
X81124Y-91722D01*
X82434Y-93471D01*
X83308Y-95513D01*
X83744Y-97846D01*
Y-100180D01*
X83308Y-102513D01*
X82434Y-104555D01*
X81124Y-106305D01*
X79595Y-107471D01*
X77849Y-107763D01*
G01X128690Y-90263D02*
X134149Y-107763D01*
X139608Y-90263D01*
G01X156016Y-107763D02*
X147282D01*
Y-90263D01*
X156016D01*
G01X152522Y-98721D02*
X147282D01*
G01X164782Y-107763D02*
Y-90263D01*
X170241D01*
X171987Y-91138D01*
X173079Y-92305D01*
X173516Y-94638D01*
X173079Y-96972D01*
X171769Y-98430D01*
X170241Y-99305D01*
X164782D01*
G01X170241D02*
X173516Y-107763D01*
G01X186649Y-108346D02*
X186212Y-108055D01*
Y-107471D01*
X186649Y-107180D01*
X187086Y-107471D01*
Y-108055D01*
X186649Y-108346D01*
G01X151649Y-152763D02*
Y-135263D01*
X149029Y-138763D01*
G01Y-152763D02*
X154269D01*
G01X163472D02*
Y-135263D01*
X169149Y-149846D01*
X174826Y-135263D01*
Y-152763D01*
G01X253482Y-90263D02*
Y-107763D01*
X262216D01*
G01X279279D02*
Y-96097D01*
G01Y-98138D02*
X278406Y-96972D01*
X277095Y-96388D01*
X275567Y-96097D01*
X274039Y-96680D01*
X272729Y-97846D01*
X271855Y-99596D01*
X271419Y-101930D01*
X271855Y-104263D01*
X272729Y-106013D01*
X274039Y-107180D01*
X275567Y-107763D01*
X277095Y-107471D01*
X278406Y-106597D01*
X279279Y-105430D01*
G01X288264Y-113013D02*
X289574Y-113596D01*
X291321Y-113013D01*
X292412Y-111847D01*
X293286Y-110388D01*
X294595Y-105722D01*
X297434Y-96097D01*
G01X290447D02*
X294595Y-105722D01*
G01X307074Y-99888D02*
X314061D01*
X313406Y-97846D01*
X312314Y-96680D01*
X310786Y-96097D01*
X309257Y-96388D01*
X307947Y-97263D01*
X307074Y-99305D01*
X306637Y-101055D01*
Y-102805D01*
X307074Y-104555D01*
X308166Y-106305D01*
X309476Y-107471D01*
X311004Y-107763D01*
X312532Y-107180D01*
X314061Y-105430D01*
G01X324792Y-107763D02*
Y-96097D01*
G01Y-98430D02*
X325884Y-97263D01*
X326976Y-96388D01*
X328504Y-96097D01*
X329595Y-96388D01*
X330906Y-97263D01*
G01X342074Y-105722D02*
X343166Y-106888D01*
X344694Y-107763D01*
X346004D01*
X347314Y-107180D01*
X348187Y-106305D01*
X348624Y-105139D01*
X348406Y-103388D01*
X347532Y-102513D01*
X343602Y-100763D01*
X342729Y-98721D01*
X343166Y-97263D01*
X344039Y-96388D01*
X345349Y-96097D01*
X346659Y-96388D01*
X347969Y-97263D01*
G01X288482Y-135263D02*
Y-152763D01*
X297216D01*
G01X310349D02*
Y-135263D01*
X307729Y-138763D01*
G01Y-152763D02*
X312969D01*
G01X404346Y-107763D02*
Y-90263D01*
X408712D01*
X410459Y-91138D01*
X411769Y-92305D01*
X412861Y-94054D01*
X413734Y-96097D01*
X413952Y-99013D01*
X413734Y-101930D01*
X412861Y-103972D01*
X411769Y-105722D01*
X410459Y-106888D01*
X408712Y-107763D01*
X404346D01*
G01X423374Y-99888D02*
X430361D01*
X429706Y-97846D01*
X428614Y-96680D01*
X427086Y-96097D01*
X425557Y-96388D01*
X424247Y-97263D01*
X423374Y-99305D01*
X422937Y-101055D01*
Y-102805D01*
X423374Y-104555D01*
X424466Y-106305D01*
X425776Y-107471D01*
X427304Y-107763D01*
X428832Y-107180D01*
X430361Y-105430D01*
G01X440874Y-105722D02*
X441966Y-106888D01*
X443494Y-107763D01*
X444804D01*
X446114Y-107180D01*
X446987Y-106305D01*
X447424Y-105139D01*
X447206Y-103388D01*
X446332Y-102513D01*
X442402Y-100763D01*
X441529Y-98721D01*
X441966Y-97263D01*
X442839Y-96388D01*
X444149Y-96097D01*
X445459Y-96388D01*
X446769Y-97263D01*
G01X461649Y-96097D02*
Y-107763D01*
G01Y-91430D02*
X461212Y-91138D01*
Y-90555D01*
X461649Y-90263D01*
X462086Y-90555D01*
Y-91138D01*
X461649Y-91430D01*
G01X476092Y-112138D02*
X477621Y-113305D01*
X479367Y-113596D01*
X480895Y-113305D01*
X482206Y-111847D01*
X483079Y-109805D01*
Y-96097D01*
G01Y-98430D02*
X482206Y-97263D01*
X480895Y-96388D01*
X479367Y-96097D01*
X477621Y-96680D01*
X476529Y-97846D01*
X475655Y-99888D01*
X475219Y-101930D01*
X475437Y-103680D01*
X476311Y-105722D01*
X477621Y-107180D01*
X479367Y-107763D01*
X480677Y-107471D01*
X482206Y-106305D01*
X483079Y-105139D01*
G01X492937Y-107763D02*
Y-96097D01*
G01Y-99013D02*
X493811Y-97555D01*
X495121Y-96388D01*
X496867Y-96097D01*
X498395Y-96388D01*
X499706Y-97555D01*
X500361Y-99596D01*
Y-107763D01*
G01X510874Y-99888D02*
X517861D01*
X517206Y-97846D01*
X516114Y-96680D01*
X514586Y-96097D01*
X513057Y-96388D01*
X511747Y-97263D01*
X510874Y-99305D01*
X510437Y-101055D01*
Y-102805D01*
X510874Y-104555D01*
X511966Y-106305D01*
X513276Y-107471D01*
X514804Y-107763D01*
X516332Y-107180D01*
X517861Y-105430D01*
G01X528592Y-107763D02*
Y-96097D01*
G01Y-98430D02*
X529684Y-97263D01*
X530776Y-96388D01*
X532304Y-96097D01*
X533395Y-96388D01*
X534706Y-97263D01*
G01X448096Y-152763D02*
Y-135263D01*
X452462D01*
X454209Y-136138D01*
X455519Y-137305D01*
X456611Y-139054D01*
X457484Y-141097D01*
X457702Y-144013D01*
X457484Y-146930D01*
X456611Y-148972D01*
X455519Y-150722D01*
X454209Y-151888D01*
X452462Y-152763D01*
X448096D01*
G01X470399Y-141097D02*
Y-152763D01*
G01Y-136430D02*
X469962Y-136138D01*
Y-135555D01*
X470399Y-135263D01*
X470836Y-135555D01*
Y-136138D01*
X470399Y-136430D01*
G01X487899Y-152763D02*
X486589Y-152471D01*
X485279Y-151305D01*
X484405Y-149263D01*
X483969Y-146930D01*
X484405Y-144596D01*
X485279Y-142555D01*
X486589Y-141388D01*
X487899Y-141097D01*
X489209Y-141388D01*
X490519Y-142555D01*
X491392Y-144596D01*
X491611Y-146930D01*
X491392Y-149263D01*
X490519Y-151305D01*
X489209Y-152471D01*
X487899Y-152763D01*
G01X575349D02*
Y-135263D01*
X572729Y-138763D01*
G01Y-152763D02*
X577969D01*
G01X588701Y-138180D02*
X590011Y-136430D01*
X591539Y-135555D01*
X593286Y-135263D01*
X595469Y-135846D01*
X596997Y-137305D01*
X597434Y-139054D01*
X597216Y-140805D01*
X596342Y-142263D01*
X591976Y-145180D01*
X590011Y-147221D01*
X588701Y-150139D01*
X588264Y-152763D01*
X597434D01*
G01X606419Y-153346D02*
X614279Y-135263D01*
G01X627849D02*
X626102Y-135846D01*
X624792Y-137305D01*
X623919Y-139054D01*
X623264Y-141388D01*
X623046Y-144013D01*
X623264Y-146638D01*
X623919Y-148972D01*
X624792Y-150722D01*
X626102Y-152180D01*
X627849Y-152763D01*
X629595Y-152180D01*
X630906Y-150722D01*
X631779Y-148972D01*
X632434Y-146638D01*
X632652Y-144013D01*
X632434Y-141388D01*
X631779Y-139054D01*
X630906Y-137305D01*
X629595Y-135846D01*
X627849Y-135263D01*
G01X644912Y-152763D02*
X645349Y-148972D01*
X646004Y-145763D01*
X646877Y-142846D01*
X647969Y-139638D01*
X649716Y-135263D01*
X640982D01*
G01X658919Y-153346D02*
X666779Y-135263D01*
G01X676201Y-138180D02*
X677511Y-136430D01*
X679039Y-135555D01*
X680786Y-135263D01*
X682969Y-135846D01*
X684497Y-137305D01*
X684934Y-139054D01*
X684716Y-140805D01*
X683842Y-142263D01*
X679476Y-145180D01*
X677511Y-147221D01*
X676201Y-150139D01*
X675764Y-152763D01*
X684934D01*
G01X697849Y-135263D02*
X696102Y-135846D01*
X694792Y-137305D01*
X693919Y-139054D01*
X693264Y-141388D01*
X693046Y-144013D01*
X693264Y-146638D01*
X693919Y-148972D01*
X694792Y-150722D01*
X696102Y-152180D01*
X697849Y-152763D01*
X699595Y-152180D01*
X700906Y-150722D01*
X701779Y-148972D01*
X702434Y-146638D01*
X702652Y-144013D01*
X702434Y-141388D01*
X701779Y-139054D01*
X700906Y-137305D01*
X699595Y-135846D01*
X697849Y-135263D01*
G01X715349Y-152763D02*
Y-135263D01*
X712729Y-138763D01*
G01Y-152763D02*
X717969D01*
G01X728701Y-138180D02*
X730011Y-136430D01*
X731539Y-135555D01*
X733286Y-135263D01*
X735469Y-135846D01*
X736997Y-137305D01*
X737434Y-139054D01*
X737216Y-140805D01*
X736342Y-142263D01*
X731976Y-145180D01*
X730011Y-147221D01*
X728701Y-150139D01*
X728264Y-152763D01*
X737434D01*
G01X623046Y-107763D02*
Y-90263D01*
X627412D01*
X629159Y-91138D01*
X630469Y-92305D01*
X631561Y-94054D01*
X632434Y-96097D01*
X632652Y-99013D01*
X632434Y-101930D01*
X631561Y-103972D01*
X630469Y-105722D01*
X629159Y-106888D01*
X627412Y-107763D01*
X623046D01*
G01X649279D02*
Y-96097D01*
G01Y-98138D02*
X648406Y-96972D01*
X647095Y-96388D01*
X645567Y-96097D01*
X644039Y-96680D01*
X642729Y-97846D01*
X641855Y-99596D01*
X641419Y-101930D01*
X641855Y-104263D01*
X642729Y-106013D01*
X644039Y-107180D01*
X645567Y-107763D01*
X647095Y-107471D01*
X648406Y-106597D01*
X649279Y-105430D01*
G01X662849Y-90263D02*
Y-107763D01*
G01X659792Y-96097D02*
X665906D01*
G01X677074Y-99888D02*
X684061D01*
X683406Y-97846D01*
X682314Y-96680D01*
X680786Y-96097D01*
X679257Y-96388D01*
X677947Y-97263D01*
X677074Y-99305D01*
X676637Y-101055D01*
Y-102805D01*
X677074Y-104555D01*
X678166Y-106305D01*
X679476Y-107471D01*
X681004Y-107763D01*
X682532Y-107180D01*
X684061Y-105430D01*
G54D101*
G01X67398Y71053D02*
X61951Y76500D01*
X41800D01*
X33410Y68110D01*
X15906D01*
G01X67998Y56553D02*
X64552D01*
X56109Y48110D01*
X15906D01*
G01X31299Y220866D02*
X28834D01*
X25500Y224200D01*
Y233700D01*
X33500Y241700D01*
Y249750D01*
X37200Y253450D01*
G01X31299Y210866D02*
Y213201D01*
X23750Y220750D01*
Y234750D01*
X27900Y238900D01*
Y246900D01*
G01X32700Y253450D02*
X25199D01*
X23596Y255053D01*
G01X32700Y253450D02*
Y251700D01*
X27900Y246900D01*
G01X27471Y262553D02*
Y269042D01*
X27900Y269471D01*
G01X32632Y264217D02*
Y264739D01*
X27900Y269471D01*
G01X31299Y358563D02*
X32913D01*
X43500Y347976D01*
Y322703D01*
X30297Y309500D01*
X20515D01*
X19283Y310732D01*
G01X36200Y318700D02*
X35950Y318450D01*
X32800D01*
X28800Y314450D01*
Y312850D01*
G01X19283Y307232D02*
Y303709D01*
X20010Y302982D01*
G01D02*
X20028Y303000D01*
X22575D01*
X24925Y305350D01*
G01X64450Y573000D02*
X63500Y572050D01*
Y572000D01*
X54101Y562601D01*
X26156D01*
X23275Y565482D01*
Y569573D01*
X23273Y569575D01*
Y572025D01*
X23275Y572027D01*
Y575344D01*
X23400Y575469D01*
Y577441D01*
X23450Y577491D01*
G01X25148Y570800D02*
X25046Y570902D01*
Y572960D01*
X25025Y572981D01*
Y574619D01*
X27100Y576694D01*
Y578100D01*
G01D02*
X29600D01*
X32850Y581350D01*
X35000D01*
G01X75700Y719050D02*
Y721000D01*
X74700Y722000D01*
X65000D01*
X51000Y736000D01*
X21087D01*
X15906Y741181D01*
G01Y761181D02*
X23319D01*
X30544Y753956D01*
X58544D01*
X67500Y745000D01*
X71650D01*
X75200Y741450D01*
G01X31299Y1054587D02*
X28113D01*
X24400Y1058300D01*
Y1074749D01*
X30050Y1080399D01*
Y1083600D01*
G01X31299Y1044587D02*
Y1048926D01*
X22650Y1057575D01*
Y1091365D01*
X24368Y1093083D01*
G01X24250Y1106000D02*
Y1102250D01*
X24500Y1102000D01*
G01D02*
X24368Y1101868D01*
Y1093083D01*
G01X15906Y1207323D02*
X26401Y1196828D01*
Y1192601D01*
X48500Y1170502D01*
Y1036500D01*
X55000Y1030000D01*
X57250D01*
X58100Y1030850D01*
G01X15906Y1187323D02*
X25177D01*
X44500Y1168000D01*
Y1016500D01*
X47950Y1013050D01*
X53800D01*
G01X31299Y1619941D02*
X25300Y1625940D01*
Y1636950D01*
X22050Y1640200D01*
G01X32900Y1664250D02*
X20400D01*
X19250Y1663100D01*
G01X31500Y1641550D02*
X26450D01*
X23700Y1644300D01*
X22050D01*
G01X31299Y1609941D02*
X34574Y1613216D01*
Y1621298D01*
X28024Y1627848D01*
Y1635024D01*
X31500Y1638500D01*
Y1641550D01*
G01X27200Y1657100D02*
X22050Y1651950D01*
Y1644300D01*
G01X18350Y1720700D02*
Y1744689D01*
X31299Y1757638D01*
G01X18350Y1720700D02*
Y1718523D01*
X16700Y1716873D01*
Y1709500D01*
X19200Y1707000D01*
G01X27292Y1714868D02*
X25732D01*
X21850Y1718750D01*
Y1720700D01*
G01X33000Y1718500D02*
X29368Y1714868D01*
X27292D01*
G01X26800Y1699200D02*
Y1695950D01*
X23650Y1692800D01*
G01X23417Y1707368D02*
X23799Y1707750D01*
X31248D01*
X32949Y1709451D01*
G01X23417Y1707368D02*
Y1702583D01*
X26800Y1699200D01*
G01X27800Y1769900D02*
X23650D01*
X23350Y1769600D01*
G01X27800Y1769900D02*
Y1766600D01*
X25000Y1763800D01*
G01X31299Y1747638D02*
X25900Y1742239D01*
Y1725150D01*
G01X20056Y1774189D02*
X20011D01*
X19000Y1775200D01*
Y1778650D01*
X21350Y1781000D01*
G01X30650Y1774400D02*
X20267D01*
X20056Y1774189D01*
G01X30250Y1787800D02*
Y1783350D01*
X27900Y1781000D01*
X21350D01*
G01X30250Y1787800D02*
X31306D01*
X37787Y1794281D01*
X37881D01*
X54050Y1810450D01*
Y1863656D01*
X29706Y1888000D01*
X23512D01*
X15906Y1880394D01*
G01Y1900394D02*
X23300Y1893000D01*
X31000D01*
X58000Y1866000D01*
Y1806500D01*
X57000Y1805500D01*
G01X95850Y68500D02*
X78500D01*
X75500Y71500D01*
G01X71400Y71704D02*
X75296D01*
X75500Y71500D01*
G01X71400Y71704D02*
X68049D01*
X67398Y71053D01*
G01X67998Y56553D02*
X71746D01*
X71802Y56497D01*
G01D02*
X75958D01*
X77953Y54502D01*
G01X78047Y61398D02*
Y54596D01*
X77953Y54502D01*
G01X49924Y153261D02*
X50539D01*
X58275Y145525D01*
X64601D01*
X74376Y155300D01*
X75300D01*
G01X56850Y187300D02*
Y191300D01*
X56600Y191550D01*
G01X39300Y175500D02*
Y174400D01*
X49700Y164000D01*
Y161500D01*
X55900Y155300D01*
X56850D01*
G01D02*
Y155800D01*
X60350Y159300D01*
G01D02*
X64400D01*
X71400Y166300D01*
X110800D01*
X143500Y199000D01*
X164197D01*
X169606Y204409D01*
G01X56850Y183300D02*
Y179300D01*
G01Y183300D02*
X45800D01*
X43700Y181200D01*
G01X56850Y163300D02*
Y167300D01*
G01D02*
X50425D01*
X43400Y174325D01*
G01X60350Y175300D02*
X63500D01*
X66000Y177800D01*
X113800D01*
X146000Y210000D01*
X150400D01*
X154400Y214000D01*
Y214500D01*
X157934Y218034D01*
X165981D01*
X169606Y214409D01*
G01X32425Y177900D02*
X32925Y177400D01*
X58250D01*
X60350Y175300D01*
G01D02*
Y171300D01*
G01X52700Y162300D02*
Y161000D01*
X54400Y159300D01*
X56850D01*
G01X60350Y167300D02*
X69100Y176050D01*
X114975D01*
X114976Y176049D01*
X116424D01*
X116425Y176050D01*
X117050D01*
X141784Y200784D01*
X151284D01*
X153300Y202800D01*
Y208104D01*
X159605Y214409D01*
X159606D01*
G01X64400Y183400D02*
X60450D01*
X60350Y183300D01*
G01X56850Y175300D02*
X52600D01*
X52500Y175200D01*
G01X60350Y187300D02*
Y191300D01*
X60600Y191550D01*
G01X60350Y187300D02*
X61314Y188264D01*
X115764D01*
X146534Y219034D01*
X153150D01*
X153900Y219784D01*
X174231D01*
X179606Y214409D01*
G01X60600Y195050D02*
X65650D01*
X70500Y190200D01*
G01X36132Y264217D02*
X36324Y264025D01*
X41424D01*
X44700Y260749D01*
Y244267D01*
X31299Y230866D01*
G01X56600Y191550D02*
X53650D01*
X53400Y191300D01*
G01X41100Y231000D02*
X42775Y229325D01*
X58573D01*
X60523Y231275D01*
X66877D01*
X80118Y218034D01*
X97084D01*
X100709Y214409D01*
G01X57400Y211350D02*
X61600D01*
G01D02*
X68200D01*
X71400Y208150D01*
G01X69900Y236600D02*
X67500Y239000D01*
X63900D01*
X62850Y240050D01*
X61000D01*
G01X77900Y229034D02*
X105334D01*
X110709Y234409D01*
G01X56900Y240050D02*
X61000D01*
G01X80709Y224409D02*
X78659D01*
X72750Y230318D01*
Y234850D01*
X73375Y235475D01*
Y251650D01*
X71750Y253275D01*
X66625D01*
X62600Y249250D01*
G01X80709Y224409D02*
X84334Y220784D01*
X102211D01*
X104400Y222973D01*
Y223227D01*
X109207Y228034D01*
X145981D01*
X149606Y224409D01*
G01X61250Y221000D02*
Y217000D01*
G01Y221000D02*
X67200D01*
X70600Y217600D01*
G01X46450Y213400D02*
Y209364D01*
X52889Y202925D01*
X64975D01*
X68866Y199034D01*
X105334D01*
X110709Y204409D01*
G01X46450Y217400D02*
Y220550D01*
X51200Y225300D01*
X68600D01*
X69400Y226100D01*
G01X74800Y231800D02*
Y233627D01*
X80473Y239300D01*
X102700D01*
X107809Y244409D01*
X110709D01*
G01X61300Y229400D02*
X58950Y227050D01*
X39450D01*
X38000Y228500D01*
G01X75300Y211300D02*
X72700Y213900D01*
X50450D01*
X49950Y213400D01*
G01X72100Y221700D02*
X70325Y223475D01*
X53474D01*
X49950Y219951D01*
Y217400D01*
G01X49700Y209700D02*
Y208849D01*
X53174Y205375D01*
X74775D01*
X78900Y209500D01*
X85800D01*
X90709Y214409D01*
G01X53500Y199700D02*
X48300D01*
X47800Y199200D01*
G01X56850Y199300D02*
Y195300D01*
X56600Y195050D01*
G01X64000Y199700D02*
X62525Y201175D01*
X58875D01*
X58500Y200800D01*
X58350D01*
X56850Y199300D01*
G01X60600Y195050D02*
Y199050D01*
X60350Y199300D01*
G01X60300Y275700D02*
X60000Y275400D01*
Y265050D01*
X58300Y263350D01*
G01X54300D02*
Y265300D01*
X57500Y268500D01*
G01X54000Y275600D02*
Y274700D01*
X48000Y268700D01*
X40615D01*
X36132Y264217D01*
G01X54300Y259850D02*
Y254900D01*
X56400Y252800D01*
G01X62600Y249250D02*
X59950D01*
X56400Y252800D01*
G01X149606Y244409D02*
X137591D01*
X133950Y248050D01*
X84350D01*
X80709Y244409D01*
G01X58300Y259850D02*
X62550D01*
X62700Y260000D01*
G01X63000Y264250D02*
Y260300D01*
X62700Y260000D01*
G01X80709Y244409D02*
Y247291D01*
X63750Y264250D01*
X63000D01*
G01X56850Y280000D02*
X48000D01*
X45800Y277800D01*
G01X43400Y272300D02*
X36250D01*
G01X36300Y328500D02*
Y325050D01*
X32550Y321300D01*
G01X36300Y328500D02*
Y333562D01*
X31299Y338563D01*
G01X32550Y321300D02*
X33600D01*
X36200Y318700D01*
G01X31299Y348563D02*
X37887D01*
X39200Y347250D01*
G01X73900Y550100D02*
X73700Y549900D01*
Y543350D01*
G01D02*
X76850D01*
X78250Y544750D01*
X81465D01*
G01X72500Y595900D02*
X72900Y596300D01*
X77000D01*
X78400Y594900D01*
Y591050D01*
G01X73700Y591000D02*
X78350D01*
X78400Y591050D01*
G01X56800Y576950D02*
X49600D01*
G01D02*
X45250D01*
X45100Y577100D01*
G01X73900Y555350D02*
Y550100D01*
G01X67700Y591000D02*
X71650Y587050D01*
Y584000D01*
G01D02*
X64850Y577200D01*
X64450D01*
G01D02*
Y573000D01*
G01X45100Y583100D02*
Y592950D01*
X45050Y593000D01*
G01D02*
X40500D01*
X39400Y591900D01*
Y581750D01*
X39000Y581350D01*
G01D02*
X35000D01*
G01X75571Y692496D02*
Y692529D01*
X75000Y693100D01*
Y700250D01*
X77200Y702450D01*
G01X51750Y688000D02*
X49674D01*
X43388Y694286D01*
G01X49500Y703500D02*
X43000D01*
X36250Y696750D01*
Y690560D01*
G01X46500Y705500D02*
X42525D01*
X33075Y696050D01*
Y688925D01*
X34000Y688000D01*
X36250D01*
G01X44500Y697500D02*
Y697000D01*
X50940Y690560D01*
X51750D01*
G01X69435Y674606D02*
Y676565D01*
X68219Y677781D01*
X65753D01*
X63875Y675903D01*
Y675824D01*
X62426Y674375D01*
X62425D01*
X61400Y673350D01*
G01X60500Y682540D02*
X60460D01*
X58250Y684750D01*
Y685440D01*
G01X60900Y670200D02*
X61400Y670700D01*
Y673350D01*
G01X42750Y685440D02*
X47590Y680600D01*
X49401D01*
X54925Y675076D01*
Y675075D01*
X56650Y673350D01*
X57400D01*
G01X57200Y667884D02*
X61884D01*
X63975Y669975D01*
X65350D01*
X66875Y671500D01*
Y674606D01*
G01X57400Y673350D02*
X57200Y673150D01*
Y667884D01*
G01X76100Y686900D02*
X71995Y682795D01*
Y681106D01*
G01X79950Y682200D02*
Y679950D01*
X81791Y678109D01*
X83850D01*
G01X77000Y727350D02*
X81450D01*
X81500Y727400D01*
G01X77000Y727350D02*
X73650D01*
X73000Y728000D01*
G01X77200Y702450D02*
X81950D01*
X82000Y702400D01*
G01X81350Y740400D02*
X76250D01*
X75200Y741450D01*
G01X75700Y719050D02*
X78200D01*
X81850Y715400D01*
G01X98900Y822900D02*
X72400D01*
G01X157800Y898000D02*
X157300Y897500D01*
X72500D01*
X62300Y887300D01*
X57800D01*
X56000Y885500D01*
G01X147500Y900500D02*
X146500Y899500D01*
X77500D01*
X76500Y900500D01*
G01X64100Y912850D02*
X64150D01*
X76500Y900500D01*
G01X43400Y896150D02*
X48550D01*
X49900Y894800D01*
G01X43400Y896150D02*
X39066D01*
X31299Y903917D01*
G01X54817Y902368D02*
Y899717D01*
X49900Y894800D01*
G01X65900Y900000D02*
X57500D01*
X55132Y902368D01*
X54817D01*
G01X64100Y909350D02*
Y904800D01*
G01X31299Y923917D02*
X35716Y919500D01*
X58600D01*
X64100Y914000D01*
Y912850D01*
G01X31299Y913917D02*
X33782Y916400D01*
X45350D01*
G01X58692Y909868D02*
X59210Y909350D01*
X64100D01*
G01X68650Y999800D02*
X65700D01*
X64200Y998300D01*
G01X54000Y996500D02*
X62400D01*
X64200Y998300D01*
G01X127200Y1015200D02*
X117200D01*
X96000Y994000D01*
X40100D01*
X37700Y991600D01*
G01X64200Y1004300D02*
Y1007750D01*
X60150Y1011800D01*
G01X68650Y1004300D02*
X64200D01*
G01X61800Y1025000D02*
Y1021850D01*
X63050Y1020600D01*
G01X61800Y1025000D02*
X54000D01*
X53500Y1025500D01*
G01X67800Y1025000D02*
X71850D01*
X72250Y1025400D01*
G01X64450Y1032100D02*
Y1028350D01*
X67800Y1025000D01*
G01X64450Y1032100D02*
X59350D01*
X58100Y1030850D01*
G01X60150Y1011800D02*
X55050D01*
X53800Y1013050D01*
G01X39000Y1033500D02*
Y1036886D01*
X31299Y1044587D01*
G01X41450Y1096000D02*
Y1084300D01*
X31299Y1074149D01*
Y1064587D01*
G01X37500Y1099823D02*
X38677D01*
X41450Y1097050D01*
Y1096000D01*
G01X31868Y1089208D02*
X34708D01*
X37200Y1091700D01*
G01X37950Y1096000D02*
Y1092450D01*
X37200Y1091700D01*
G01X67302Y1133490D02*
Y1136798D01*
X65547Y1138553D01*
X63198D01*
G01D02*
X63202Y1138549D01*
Y1134147D01*
G01X81398Y1137953D02*
X77008D01*
X77002Y1137947D01*
G01X78292Y1148041D02*
X77961D01*
X75819Y1145899D01*
Y1139130D01*
X77002Y1137947D01*
G01X71150Y1144500D02*
X70202Y1143552D01*
Y1138347D01*
G01X63202Y1128147D02*
X66370Y1131315D01*
X68204D01*
X70202Y1133313D01*
Y1138347D01*
G01X63498Y1123853D02*
X63202Y1124149D01*
Y1128147D01*
G01X70500Y1161500D02*
Y1145150D01*
X71150Y1144500D01*
G01X86950Y1143000D02*
Y1144993D01*
X73163Y1158780D01*
G01X31299Y1629941D02*
Y1633799D01*
X38000Y1640500D01*
Y1659150D01*
X32900Y1664250D01*
G01X35375Y1649050D02*
Y1653825D01*
X32900Y1656300D01*
G01D02*
Y1660750D01*
G01X32949Y1709451D02*
X35500Y1712002D01*
Y1733437D01*
X31299Y1737638D01*
G01X45300Y1776300D02*
X48850Y1772750D01*
Y1770300D01*
X49350Y1769800D01*
G01X54500Y1764700D02*
X54450D01*
X49350Y1769800D01*
G01X33800Y1769900D02*
Y1771200D01*
X31600Y1773400D01*
Y1773450D01*
X30650Y1774400D01*
G01X48250Y1760300D02*
Y1764450D01*
X48500Y1764700D01*
G01X41600Y1767550D02*
Y1762100D01*
X45700Y1758000D01*
X46050D01*
X48250Y1755800D01*
G01D02*
X48300Y1755750D01*
G01X48250Y1760300D02*
Y1755800D01*
G01X48500Y1764700D02*
Y1765000D01*
X45300Y1768200D01*
Y1772600D01*
X43200Y1774700D01*
Y1780700D01*
X45150Y1782650D01*
Y1793650D01*
X57000Y1805500D01*
G01X84047Y61398D02*
X88149D01*
X88253Y61502D01*
G01D02*
Y65500D01*
G01X85750Y71500D02*
X81500D01*
G01Y75500D02*
Y71500D01*
G01X179606Y224409D02*
X175981Y228034D01*
X158103D01*
X154700Y224631D01*
Y224200D01*
X151284Y220784D01*
X114334D01*
X110709Y224409D01*
G01X117600Y234900D02*
X121100D01*
X124234Y238034D01*
X175981D01*
X179606Y234409D01*
G01Y244409D02*
X183200Y240815D01*
Y235942D01*
X183231Y235911D01*
Y232907D01*
X183200Y232876D01*
Y232300D01*
X181684Y230784D01*
X122784D01*
X122100Y230100D01*
G01X179606Y204409D02*
X184980Y209783D01*
Y232181D01*
X184981Y232182D01*
Y236636D01*
X184980Y236637D01*
Y245320D01*
X182266Y248034D01*
X176934D01*
X174200Y245300D01*
Y243484D01*
X171500Y240784D01*
X124484D01*
X122700Y239000D01*
X110173D01*
X107000Y235827D01*
Y235573D01*
X102211Y230784D01*
X85992D01*
X85676Y231100D01*
G01X127200Y246000D02*
X121984Y240784D01*
X107084D01*
X100709Y234409D01*
G01X128900Y588646D02*
X128892Y588654D01*
X124900D01*
G01X120520Y612629D02*
Y598980D01*
X120800Y598700D01*
G01D02*
Y593900D01*
X124900Y589800D01*
Y588654D01*
G01X129000Y597000D02*
Y599030D01*
X127810Y600220D01*
Y600254D01*
X124455Y603609D01*
Y612629D01*
G01X132735Y593429D02*
Y597770D01*
X129560Y600945D01*
Y600979D01*
X126425Y604114D01*
Y612629D01*
G01X105000Y603200D02*
Y598950D01*
X103500Y597450D01*
G01X97265Y597521D02*
X98808Y599064D01*
Y604821D01*
X99578Y605591D01*
Y605771D01*
G01X102835Y618504D02*
Y605028D01*
X101105Y603298D01*
Y597861D01*
X97265Y594021D01*
G01X112018Y574741D02*
Y584900D01*
G01X112645Y612629D02*
Y608442D01*
X110200Y605997D01*
Y594650D01*
X111150Y593700D01*
G01D02*
X110500Y593050D01*
Y586418D01*
X112018Y584900D01*
G01X107650Y593700D02*
X108500Y592850D01*
Y587500D01*
X106400Y585400D01*
Y580558D01*
X106338Y580496D01*
G01X104518Y570866D02*
X106338Y572686D01*
Y580496D01*
G01X110675Y612629D02*
Y608947D01*
X108450Y606722D01*
Y594500D01*
X107650Y593700D01*
G01X112018Y566991D02*
X108393D01*
X104518Y570866D01*
G01X116450Y603500D02*
Y597350D01*
X116000Y596900D01*
G01X118550Y612629D02*
Y608242D01*
X118565Y608227D01*
Y592846D01*
G01X116800Y588646D02*
X120792D01*
X120800Y588654D01*
G01X118565Y592846D02*
X118700D01*
X119692Y591854D01*
X119700D01*
X120800Y590754D01*
Y588654D01*
G01X125835Y593629D02*
Y598155D01*
X122490Y601500D01*
Y612629D01*
G01X93065Y597521D02*
Y599630D01*
X94545Y601110D01*
Y601197D01*
G01X96500Y567600D02*
Y563700D01*
X96300Y563500D01*
G01X91300Y569750D02*
X94350D01*
X96500Y567600D01*
G01X89335Y561050D02*
Y567785D01*
X91300Y569750D01*
G01X96300Y563500D02*
X98800D01*
X101500Y560800D01*
X105100D01*
X107600Y558300D01*
G01D02*
Y556800D01*
X112600Y551800D01*
X115300D01*
G01X138900Y650100D02*
X138599Y650401D01*
X132001D01*
X130360Y648760D01*
Y646029D01*
G01X139200Y653900D02*
X138900Y654200D01*
X133300D01*
X128395Y649295D01*
Y646029D01*
G01X102835Y632284D02*
X97816D01*
X93800Y636300D01*
Y646100D01*
X81100Y658800D01*
Y668200D01*
X80900Y668400D01*
G01X131135Y639554D02*
Y637435D01*
X125500Y631800D01*
X109965D01*
X108479Y630314D01*
X102835D01*
G01Y636219D02*
X99085D01*
X97300Y638004D01*
Y647551D01*
X86443Y658408D01*
Y662853D01*
G01X102835Y638189D02*
X99590D01*
X99050Y638729D01*
Y648276D01*
X88967Y658359D01*
Y659749D01*
G01X102835Y634249D02*
X98326D01*
X95550Y637025D01*
Y646826D01*
X94526Y647850D01*
X94525D01*
X91750Y650625D01*
Y650626D01*
X84268Y658108D01*
Y665568D01*
X84504Y665804D01*
Y666353D01*
G01X90674Y663367D02*
Y662969D01*
X91700Y661943D01*
Y658101D01*
X102835Y646966D01*
Y640154D01*
G01X90630Y602020D02*
X92465Y603855D01*
Y606921D01*
G01X128395Y612629D02*
Y605469D01*
X131935Y601929D01*
G01X140135Y593229D02*
Y598129D01*
X130360Y607904D01*
Y612629D01*
G01X108710D02*
Y609710D01*
X105000Y606000D01*
Y603200D01*
G01X112800Y653500D02*
Y652573D01*
X114615Y650758D01*
Y646029D01*
G01X108200Y655825D02*
Y652223D01*
X110675Y649748D01*
Y646029D01*
G01X99578Y605771D02*
X98800Y606549D01*
Y620100D01*
X99169Y620469D01*
X102835D01*
G01Y628344D02*
X93790D01*
X93063Y629071D01*
Y629134D01*
G01X89435Y635029D02*
Y632762D01*
X93063Y629134D01*
G01X122088Y665912D02*
Y656311D01*
X120520Y654743D01*
Y646029D01*
G01X115600Y656750D02*
X115400Y656550D01*
Y652448D01*
X116580Y651268D01*
Y646029D01*
G01X111400Y658500D02*
Y655600D01*
X110625Y654825D01*
Y652273D01*
X112645Y650253D01*
Y646029D01*
G01X108710D02*
X107771D01*
X101900Y651900D01*
Y654100D01*
G01X102835Y618504D02*
X107504D01*
X110035Y621035D01*
Y621136D01*
X113306Y624407D01*
X113403D01*
X113405Y624409D01*
X136235D01*
G01X122500Y653650D02*
X122490Y653640D01*
Y646029D01*
G01X118550D02*
Y651950D01*
X117400Y653100D01*
G01X116580Y612629D02*
Y603630D01*
X116450Y603500D01*
G01X112950D02*
Y600068D01*
X113655Y599363D01*
G01X114615Y612629D02*
Y605165D01*
X112950Y603500D01*
G01X94545Y601197D02*
X95850Y602502D01*
Y619625D01*
X98664Y622439D01*
X102835D01*
G01X92971Y617335D02*
Y619871D01*
X97509Y624409D01*
X102835D01*
G01X125202Y657500D02*
X124455Y656753D01*
Y646029D01*
G01X92465Y610421D02*
X90425Y612461D01*
Y622105D01*
X91463Y623143D01*
G01X102835Y626374D02*
X94694D01*
X91463Y623143D01*
G01X126425Y646029D02*
Y651025D01*
X129000Y653600D01*
G01X129335Y662079D02*
Y666136D01*
X132488Y669289D01*
X138788D01*
X142648Y665429D01*
G01X121500Y683500D02*
X125641D01*
X125806Y683665D01*
G01X113306Y682415D02*
X120415D01*
X121500Y683500D01*
G01X113306Y687415D02*
X119076D01*
X119483Y687008D01*
X119576D01*
G01D02*
X124749D01*
X125806Y688065D01*
G01X120702Y690847D02*
X124588D01*
X125906Y692165D01*
G01X113306Y692415D02*
X119134D01*
X120702Y690847D01*
G01X93206Y677415D02*
Y672544D01*
X94750Y671000D01*
G01X100600Y670600D02*
X95150D01*
X94750Y671000D01*
G01X116300Y667150D02*
X120850D01*
X122088Y665912D01*
G01X115600Y656750D02*
X119150D01*
X119300Y656600D01*
G01X104900Y658750D02*
X111150D01*
X111400Y658500D01*
G01X81994Y694635D02*
X85495D01*
X86060Y695200D01*
G01X82006Y690465D02*
X81994Y690477D01*
Y694635D01*
G01X86060Y695200D02*
Y693255D01*
X86900Y692415D01*
X93206D01*
G01X84150Y686400D02*
Y682900D01*
X83450Y682200D01*
G01X93206Y687415D02*
X88485D01*
X86000Y689900D01*
G01X84150Y686400D02*
Y688050D01*
X86000Y689900D01*
G01X93206Y682415D02*
X87909D01*
X86597Y681103D01*
G01X100200Y663900D02*
X101500Y665200D01*
X104400D01*
X107800Y668600D01*
X110850D01*
X112850Y670600D01*
G01X129335Y658579D02*
X126281D01*
X125202Y657500D01*
G01X129000Y653600D02*
X133535Y658135D01*
Y658579D01*
G01X116350Y670600D02*
X116300D01*
X114425Y668725D01*
Y665875D01*
X116900Y663400D01*
X118127D01*
G01D02*
X119050Y662477D01*
Y660200D01*
G01X104900Y662250D02*
X104850Y662200D01*
G01X109005Y665890D02*
X108540D01*
X104900Y662250D01*
G01X95200D02*
X95950Y661500D01*
X104150D01*
X104850Y662200D01*
G01X115550Y660200D02*
X114000Y661750D01*
Y663350D01*
G01D02*
X109500D01*
X108350Y662200D01*
G01X81500Y733400D02*
X86250D01*
G01X81350Y740400D02*
Y733550D01*
X81500Y733400D01*
G01X82000Y708400D02*
X87250D01*
X87750Y707900D01*
G01X81850Y715400D02*
Y708550D01*
X82000Y708400D01*
G01X105940Y846304D02*
Y841241D01*
X106404Y840777D01*
Y840700D01*
G01X100825Y846304D02*
Y841525D01*
X100300Y841000D01*
G01X111060Y846304D02*
Y851160D01*
X111500Y851600D01*
G01X98700Y877100D02*
X101500Y874300D01*
Y874200D01*
G01X102300Y863438D02*
X103380Y864518D01*
Y868504D01*
G01X108500D02*
Y863621D01*
X107164Y862285D01*
G01X113620Y868504D02*
Y862420D01*
X113400Y862200D01*
G01X110500Y939750D02*
Y942500D01*
X106050Y946950D01*
Y951350D01*
X108200Y953500D01*
G01D02*
X110494Y955794D01*
X112529D01*
G01D02*
X113960Y957225D01*
Y963000D01*
G01X112984Y946835D02*
X115054Y948905D01*
Y953554D01*
X117294Y955794D01*
X117529D01*
G01D02*
X116520Y956803D01*
Y963000D01*
G01X112984Y946835D02*
X112800Y946651D01*
Y944250D01*
X117300Y939750D01*
G01X120054Y945600D02*
Y941423D01*
X121671Y939806D01*
G01X119080Y963000D02*
Y959243D01*
X122529Y955794D01*
G01D02*
X122528D01*
X120054Y953320D01*
Y945600D01*
G01X131500Y947850D02*
Y949500D01*
X130000Y951000D01*
Y957275D01*
X130903Y958178D01*
G01X123300Y1001350D02*
Y1001400D01*
X140798Y1018898D01*
X142998D01*
X143000Y1018900D01*
X146800D01*
G01X119300Y1001350D02*
X138898Y1020948D01*
X142148D01*
X143900Y1022700D01*
G01X110400Y997850D02*
X114800D01*
G01D02*
Y997720D01*
X116520Y996000D01*
Y985200D01*
G01X119300Y997850D02*
X119080Y997630D01*
Y992900D01*
G01D02*
Y985200D01*
G01X123300Y997850D02*
X123850Y998400D01*
X127700D01*
G01X121640Y985200D02*
Y996190D01*
X123300Y997850D01*
G01X130903Y958178D02*
Y958403D01*
X132000Y959500D01*
X137340D01*
G01X135000Y999750D02*
X134150D01*
X130900Y1003000D01*
Y1003400D01*
G01X81398Y1126153D02*
X81498Y1126253D01*
Y1131853D01*
X81398Y1131953D01*
G01X88502Y1136247D02*
X84208Y1131953D01*
X81398D01*
G01X88502Y1136247D02*
Y1139148D01*
X86950Y1140700D01*
Y1143000D01*
G01X112018Y1263718D02*
X116782D01*
X119500Y1261000D01*
G01X112018Y1255968D02*
X119000D01*
G01X104518Y1259843D02*
X108143D01*
X112018Y1255968D01*
G01X113800Y1399700D02*
X111600D01*
X111000Y1400300D01*
Y1404400D01*
X111600Y1405000D01*
X113050D01*
X115350Y1407300D01*
Y1408200D01*
G01X128700Y1408000D02*
X127129Y1406429D01*
X123171D01*
X121400Y1408200D01*
X115350D01*
G01X121125Y1401954D02*
X119500Y1400329D01*
Y1392000D01*
X117000Y1389500D01*
Y1387500D01*
G01D02*
X119000Y1385500D01*
X122862D01*
G01D02*
X141000D01*
X143000Y1387500D01*
G01X129000Y1416425D02*
X131475D01*
X135000Y1412900D01*
Y1411854D01*
G01X113800Y1402260D02*
X115740D01*
X117399Y1400601D01*
Y1394000D01*
X115399Y1392000D01*
X99000D01*
X97500Y1390500D01*
Y1382500D01*
X99500Y1380500D01*
X165000D01*
G01X99500Y1407500D02*
X100100Y1408100D01*
X104050D01*
G01D02*
Y1406550D01*
X105600Y1405000D01*
X107700D01*
X109200Y1403500D01*
Y1400600D01*
G01D02*
Y1397940D01*
X108400Y1397140D01*
X106400D01*
G01Y1399700D02*
X108300D01*
X109200Y1400600D01*
G01X135601Y1416200D02*
X134900D01*
X132500Y1418600D01*
X126200D01*
X124050Y1420750D01*
X123000D01*
G01X134500Y1420000D02*
X133800Y1420700D01*
X127550D01*
X127500Y1420750D01*
G01X117100Y1430100D02*
X118000Y1429200D01*
Y1424250D01*
G01X119559Y1442400D02*
Y1432559D01*
X117100Y1430100D01*
G01X109500Y1438000D02*
X112575D01*
X114441Y1439866D01*
Y1442400D01*
G01X95600Y1420250D02*
X91500D01*
G01X98500Y1428400D02*
X98100Y1428000D01*
Y1421500D01*
X96850Y1420250D01*
X95600D01*
G01X123000Y1424250D02*
Y1431300D01*
G01D02*
Y1441518D01*
X122118Y1442400D01*
G01X127500Y1424250D02*
X126975Y1424775D01*
Y1435400D01*
G01D02*
Y1446357D01*
X127013Y1446395D01*
Y1446469D01*
X126600Y1446882D01*
G01X136771Y548521D02*
X136779Y548513D01*
Y543121D01*
G01D02*
X136950Y542950D01*
X145265D01*
G01X182588Y542288D02*
X175776Y549100D01*
X172100D01*
G01X144329Y598765D02*
X142525Y600569D01*
Y617660D01*
X139716Y620469D01*
X136235D01*
G01X136679Y553721D02*
Y548613D01*
X136771Y548521D01*
G01X158000Y575150D02*
X157100Y574250D01*
Y565400D01*
X160000Y562500D01*
G01X165900Y553300D02*
X160300Y558900D01*
Y559000D01*
X154750Y564550D01*
Y565300D01*
X153500Y566550D01*
G01X153135Y559250D02*
Y566185D01*
X153500Y566550D01*
G01X172100Y549100D02*
X170100D01*
X165900Y553300D01*
G01X147900Y588100D02*
X151650D01*
X152750Y587000D01*
G01X152700Y618803D02*
Y618700D01*
X155779Y615621D01*
Y615065D01*
G01X136235Y632284D02*
X142751D01*
X150345Y624690D01*
X154590D01*
X156700Y626800D01*
G01X170200Y623650D02*
Y620098D01*
X170349Y619949D01*
G01X139929Y604165D02*
X140775Y605011D01*
Y616935D01*
X139206Y618504D01*
X136235D01*
G01X151029Y627565D02*
X150072D01*
X143388Y634249D01*
X136235D01*
G01X160700Y615900D02*
X158700D01*
X153410Y621190D01*
X148895D01*
X141741Y628344D01*
X136235D01*
G01X180365Y645821D02*
Y646635D01*
X174100Y652900D01*
G01X171370Y645839D02*
Y650170D01*
X174100Y652900D01*
G01X136235Y624409D02*
X140726D01*
X146200Y618935D01*
Y616159D01*
X150023Y612336D01*
X160814D01*
X162125Y611025D01*
Y611024D01*
X163574Y609575D01*
X163575D01*
X164600Y608550D01*
G01X170100Y607600D02*
X175265D01*
X176300Y608635D01*
G01X170100Y607600D02*
X165550D01*
X164600Y608550D01*
G01X176221Y613535D02*
Y608714D01*
X176300Y608635D01*
G01X136235Y630314D02*
X142246D01*
X149620Y622940D01*
X155060D01*
X157200Y620800D01*
G01X162650Y622700D02*
X160750Y620800D01*
X157200D01*
G01X151335Y632379D02*
X148335D01*
X146663Y634051D01*
G01X136235Y636219D02*
X144495D01*
X146663Y634051D01*
G01X136235Y626374D02*
X141236D01*
X148595Y619015D01*
Y618300D01*
G01D02*
X151830Y615065D01*
X152279D01*
G01X151335Y640400D02*
Y635879D01*
G01X159800Y634819D02*
X152395D01*
X151335Y635879D01*
G01X136235Y640154D02*
X140754D01*
X145200Y644600D01*
G01D02*
X146383Y645783D01*
Y648684D01*
X145188Y649879D01*
X144235D01*
G01X153200Y653200D02*
X149879Y649879D01*
X148435D01*
G01D02*
Y643735D01*
X142889Y638189D01*
X136235D01*
G01X146365Y611271D02*
X147390Y610246D01*
X147391D01*
X148666Y608971D01*
X152265D01*
G01D02*
X157627D01*
X158535Y609879D01*
G01X163100Y604717D02*
Y605314D01*
X158535Y609879D01*
G01X136235Y622439D02*
X140221D01*
X144400Y618260D01*
Y613236D01*
X146365Y611271D01*
G01X166150Y626700D02*
Y622700D01*
G01X170200Y627150D02*
X166600D01*
X166150Y626700D01*
G01X170200Y627150D02*
X171400D01*
X174250Y624300D01*
G01X179017Y620013D02*
X177487D01*
X174250Y623250D01*
Y624300D01*
G01X154500Y687250D02*
X151550D01*
X151025Y687775D01*
X150978D01*
G01X151432Y661741D02*
X149092D01*
X145800Y658449D01*
Y654944D01*
X144235Y653379D01*
G01X148435D02*
Y658008D01*
X148995Y658568D01*
G01X133535Y658579D02*
X137723D01*
X137765Y658621D01*
G01X158500Y695000D02*
X159515Y696015D01*
X159633D01*
X160500Y696882D01*
Y699000D01*
X163300Y701800D01*
Y702300D01*
G01X161500Y691700D02*
X158500Y694700D01*
Y695000D01*
G01X150700Y691700D02*
X149904Y690904D01*
X148504D01*
X147350Y689750D01*
X145500D01*
G01X144250Y695500D02*
Y691000D01*
X145500Y689750D01*
G01X141625Y682250D02*
Y677875D01*
X144500Y675000D01*
X145500D01*
G01D02*
X146000Y674500D01*
X152500D01*
X153000Y675000D01*
Y682250D01*
X154500Y683750D01*
G01X171750Y701100D02*
X169150D01*
X167700Y699650D01*
G01D02*
Y703200D01*
X167600Y703300D01*
G01X155825Y710104D02*
X151146D01*
X149500Y711750D01*
G01D02*
X145000D01*
G01X163500Y710104D02*
Y702500D01*
X163300Y702300D01*
G01X158500Y702750D02*
X162850D01*
X163300Y702300D01*
G01X153192Y705890D02*
Y705308D01*
X154500Y704000D01*
Y702750D01*
G01D02*
X157250Y705500D01*
X160000D01*
X160940Y706440D01*
Y710104D01*
G01X166060D02*
Y704840D01*
X167600Y703300D01*
G01X168620Y710104D02*
Y706780D01*
X169800Y705600D01*
X178100D01*
X179000Y706500D01*
G01X143000Y953032D02*
Y953525D01*
X145020Y955545D01*
Y959500D01*
G01X143000Y953032D02*
Y951250D01*
X145000Y949250D01*
G01X147580Y959500D02*
Y954110D01*
X146500Y953030D01*
G01D02*
Y951750D01*
X149000Y949250D01*
G01X150140Y959500D02*
Y954829D01*
X149772Y954461D01*
Y954121D01*
G01D02*
Y953917D01*
X150830Y952859D01*
Y951420D01*
X153000Y949250D01*
G01X152700Y959500D02*
Y952521D01*
X152747Y952474D01*
G01D02*
X153776D01*
X157000Y949250D01*
G01X133500Y953000D02*
Y950350D01*
X136000Y947850D01*
G01X133500Y953000D02*
X135500Y955000D01*
X139500D01*
X139900Y955400D01*
Y959500D01*
G01X142460D02*
Y955460D01*
X139500Y952500D01*
Y951500D01*
G01D02*
Y948850D01*
X140500Y947850D01*
G01X135000Y1003250D02*
Y1005500D01*
X146800Y1017300D01*
Y1018900D01*
G01X139100Y1003150D02*
Y1006200D01*
X148975Y1016075D01*
Y1019801D01*
X146076Y1022700D01*
X143900D01*
G01X152700Y981700D02*
Y987450D01*
X159500Y994250D01*
G01X152700Y981700D02*
Y978700D01*
X150500Y976500D01*
G01X155260Y981700D02*
Y974760D01*
X155000Y974500D01*
G01X155260Y981700D02*
Y986260D01*
X163250Y994250D01*
X163500D01*
G01X147580Y981700D02*
Y994580D01*
X147600Y994600D01*
G01X147900Y999650D02*
Y994900D01*
X147600Y994600D01*
G01X143100Y1007100D02*
Y1007000D01*
X141150Y1005050D01*
Y1001250D01*
X139550Y999650D01*
X139100D01*
G01D02*
Y992900D01*
X142500Y989500D01*
Y981740D01*
X142460Y981700D01*
G01X145020D02*
Y991480D01*
X142000Y994500D01*
G01X143800Y999750D02*
Y996300D01*
X142000Y994500D01*
G01X139900Y981700D02*
Y989200D01*
X136475Y992625D01*
Y998275D01*
X135000Y999750D01*
G01X150140Y981700D02*
Y990640D01*
X154000Y994500D01*
G01X152100Y999750D02*
Y996400D01*
X154000Y994500D01*
G01X135000Y1408354D02*
Y1404354D01*
X134700Y1404054D01*
G01X135696Y1392300D02*
X137500Y1394104D01*
Y1402000D01*
X135446Y1404054D01*
X134700D01*
G01X143000Y1387500D02*
X139500Y1391000D01*
X136996D01*
X135696Y1392300D01*
G01X159774Y1414374D02*
X159148Y1415000D01*
X155546D01*
G01X151900Y1408954D02*
X148358D01*
X141100Y1401696D01*
G01X155546Y1415000D02*
Y1412600D01*
X151900Y1408954D01*
G01X151454Y1394000D02*
X161500D01*
X165000Y1390500D01*
G01X151454Y1394000D02*
X151100Y1394354D01*
Y1398100D01*
X148025Y1401175D01*
Y1401454D01*
G01X155546Y1419200D02*
X158025D01*
X163500Y1413725D01*
Y1406600D01*
X162000Y1405100D01*
X149300D01*
X148025Y1403825D01*
Y1401454D01*
G01X135000Y1411854D02*
X139342D01*
X141100Y1410096D01*
G01X155550Y1423400D02*
X156300D01*
X169900Y1409800D01*
Y1375400D01*
X165000Y1370500D01*
G01X152331Y1431131D02*
X156631D01*
G01D02*
X160891Y1435391D01*
Y1444113D01*
X158600Y1446404D01*
G01X165500Y1450600D02*
X168369D01*
X169369Y1449600D01*
Y1444969D01*
G01X158600Y1446404D02*
X159696Y1447500D01*
X160500D01*
X163600Y1450600D01*
X165500D01*
G01X142500Y1420500D02*
X143900Y1421900D01*
Y1425800D01*
X156104Y1438004D01*
X158600D01*
G01X133250Y1428300D02*
X135050Y1426500D01*
X136894D01*
X138694Y1424700D01*
Y1422269D01*
G01X133250Y1428300D02*
Y1432000D01*
G01X142500Y1420500D02*
X140731Y1422269D01*
X138694D01*
G01X147500Y1437250D02*
X144954D01*
X139704Y1432000D01*
X133250D01*
G01X160831Y1426831D02*
X157431D01*
X156631Y1427631D01*
G01D02*
Y1424481D01*
X155550Y1423400D01*
G54D10*
G01X67250Y63500D02*
Y62045D01*
X63315Y58110D01*
X15906D01*
G01X27000Y573800D02*
X27100Y573900D01*
X29000D01*
X30000Y572900D01*
Y571176D01*
X29950Y571126D01*
Y570800D01*
G01X15906Y751181D02*
X19000Y748087D01*
Y743500D01*
X23500Y739000D01*
X52500D01*
X61500Y730000D01*
X65250D01*
G01X15906Y1197323D02*
X18883D01*
X46475Y1169731D01*
Y1022525D01*
X51000Y1018000D01*
G01X15906Y1890394D02*
X30106D01*
X56025Y1864475D01*
Y1809125D01*
X39206Y1792306D01*
X39179D01*
G01X67250Y63500D02*
X63500D01*
G01X78600Y571050D02*
X78950D01*
X82400Y574500D01*
X82900D01*
G01X83430Y561050D02*
Y565370D01*
X80600Y568200D01*
X76300D01*
X74100Y570400D01*
G01D02*
X70400Y566700D01*
Y565500D01*
G01X65250Y730000D02*
X65500Y729750D01*
Y726481D01*
X67981Y724000D01*
X86000D01*
X86500Y723500D01*
G01X51200Y827000D02*
X53000Y825200D01*
X108050D01*
X111200Y828350D01*
G01X61207D02*
X98800D01*
X98804Y828346D01*
X102900D01*
G01X102600Y884850D02*
X69750D01*
X67600Y882700D01*
X64600D01*
G01X110900Y884850D02*
X106800D01*
X104600Y887050D01*
X68838D01*
X66988Y885200D01*
X61600D01*
G01X119300Y884850D02*
X115100D01*
Y885000D01*
X110700Y889400D01*
X67800D01*
X67200Y888800D01*
G01X70800Y981600D02*
X72350Y980050D01*
X77400D01*
G01X76800Y986600D02*
X80800D01*
X81500Y985900D01*
G01X77400Y980050D02*
Y981900D01*
X81400Y985900D01*
X81500D01*
G01X51000Y1018000D02*
X51500Y1017500D01*
X68950D01*
X72350Y1020900D01*
G01X68750Y1175100D02*
Y1178750D01*
X68800Y1178800D01*
G01X78752Y1619703D02*
X83000D01*
G01X83050Y1616000D02*
X81500D01*
X78797Y1613297D01*
X78752D01*
G01X39179Y1792306D02*
X38606D01*
X34950Y1788650D01*
Y1788200D01*
G01X87370Y544750D02*
Y538320D01*
X86850Y537800D01*
G01X89335Y544750D02*
Y538815D01*
X90350Y537800D01*
G01X87150Y569900D02*
X87370Y569680D01*
Y561050D01*
G01X87150Y569900D02*
Y573900D01*
X87400Y574150D01*
G01D02*
X86650Y574900D01*
X86300D01*
X83619Y577581D01*
Y581742D01*
G01X82900Y574500D02*
X83650Y573750D01*
Y569900D01*
G01D02*
Y568850D01*
X85400Y567100D01*
Y561050D01*
G01X116175Y846304D02*
Y843225D01*
X118700Y840700D01*
G01X113620Y846304D02*
Y840180D01*
X116800Y837000D01*
X119300D01*
G01D02*
X119600Y836700D01*
Y831850D01*
G01X87446Y852900D02*
X92300D01*
X94138Y854738D01*
X111362D01*
X113600Y852500D01*
Y852300D01*
X113620Y852280D01*
Y846304D01*
G01X108500D02*
Y841770D01*
X108504Y841766D01*
Y839634D01*
X108502Y839632D01*
Y834518D01*
X110620Y832400D01*
X110650D01*
X111200Y831850D01*
G01X87446Y848500D02*
X92000D01*
X92400Y848900D01*
G01D02*
X96038Y852538D01*
X106262D01*
X108500Y850300D01*
Y846304D01*
G01X103380D02*
Y849420D01*
X102462Y850338D01*
X98038D01*
X91800Y844100D01*
X87446D01*
G01X103400Y838300D02*
X103380Y838320D01*
Y846304D01*
G01X102900Y831846D02*
X103400Y832346D01*
Y838300D01*
G01X119600Y828350D02*
X119150D01*
X114900Y824100D01*
G01X87450Y865700D02*
X92400D01*
X92800Y865300D01*
G01X102600Y881350D02*
X103565Y880385D01*
Y876465D01*
X105940Y874090D01*
Y868504D01*
G01D02*
Y864108D01*
X103170Y861338D01*
X96762D01*
X92800Y865300D01*
G01X111060Y868504D02*
Y863211D01*
X106987Y859138D01*
X95762D01*
X93900Y861000D01*
X87950D01*
X87450Y861500D01*
G01X111100Y876700D02*
X111060Y876660D01*
Y868504D01*
G01X110900Y881350D02*
X111060Y881190D01*
Y876740D01*
X111100Y876700D01*
G01X119300Y881350D02*
X116175Y878225D01*
Y868504D01*
G01D02*
Y861375D01*
X111738Y856938D01*
X93862D01*
X92700Y858100D01*
G01X87450Y857200D02*
X91800D01*
X92700Y858100D01*
G01X94000Y957000D02*
X94500Y957500D01*
G01D02*
X97000D01*
X103500Y964000D01*
Y966500D01*
G01X130800Y981600D02*
Y985800D01*
X129900Y986700D01*
G01X81850Y966200D02*
X82150Y965900D01*
X87600D01*
G01X88000Y972550D02*
Y966300D01*
X87600Y965900D01*
G01X99000Y979750D02*
X103250D01*
X103500Y980000D01*
G01X99000Y979750D02*
X97250D01*
X94500Y982500D01*
G01D02*
Y984000D01*
X90542Y987958D01*
G01D02*
X89958D01*
X88000Y986000D01*
Y980050D01*
G01X97958Y966958D02*
X94000Y963000D01*
G01X99000Y976250D02*
Y968000D01*
X97958Y966958D01*
G01X103500Y974000D02*
Y966500D01*
G01X100500Y1420250D02*
Y1417500D01*
X99600Y1416600D01*
Y1416500D01*
G01X131174Y1412700D02*
X128246D01*
X125000Y1409454D01*
G01X100000Y1443000D02*
Y1444154D01*
X105287Y1449441D01*
X107400D01*
G01X94750Y1434900D02*
X100000Y1440150D01*
Y1443000D01*
G01X111833Y1469667D02*
Y1468367D01*
X114441Y1465759D01*
Y1461600D01*
G01X83500Y1461750D02*
X89450D01*
X89500Y1461700D01*
G01X95500Y1460750D02*
X90450D01*
X89500Y1461700D01*
G01X95500Y1460750D02*
X101000D01*
G01D02*
Y1460500D01*
X104382Y1457118D01*
X107400D01*
G01X91250Y1451000D02*
X86900D01*
G01X93500Y1475750D02*
Y1475000D01*
X101500Y1467000D01*
X109500D01*
X111882Y1464618D01*
Y1461600D01*
G01X100200Y1433800D02*
X97900Y1431500D01*
X94750D01*
G01X107400Y1446882D02*
Y1443900D01*
X100200Y1436700D01*
Y1433800D01*
G01X126600Y1449441D02*
X130223D01*
X132064Y1447600D01*
X133000D01*
G01X111882Y1442400D02*
X109900D01*
X104500Y1437000D01*
Y1431000D01*
X103000Y1429500D01*
G01X109650Y1425900D02*
Y1429150D01*
X110000Y1429500D01*
G01X105000Y1423750D02*
X107500D01*
X109650Y1425900D01*
G01X100500Y1423750D02*
X105000D01*
G01X103000Y1429500D02*
X100500Y1427000D01*
Y1423750D01*
G01X132000Y1436500D02*
X140071D01*
X147000Y1443429D01*
Y1445071D01*
X150929Y1449000D01*
X154000D01*
X155000Y1450000D01*
X160000D01*
X163000Y1453000D01*
X168763D01*
X171869Y1449894D01*
Y1441869D01*
X167469Y1437469D01*
X165494D01*
G01X117000Y1461600D02*
Y1479800D01*
X121300Y1484100D01*
Y1497950D01*
X121000Y1498250D01*
G01X125000D02*
X123750Y1497000D01*
Y1483250D01*
X119559Y1479059D01*
Y1461600D01*
G01X113150Y1425900D02*
Y1431350D01*
X117000Y1435200D01*
G01X113150Y1421600D02*
Y1425900D01*
G01X117000Y1435200D02*
Y1442400D01*
G01X106770Y1480640D02*
Y1486020D01*
X107500Y1486750D01*
G01X107000Y1474500D02*
X106770Y1474730D01*
Y1480640D01*
G01X107000Y1474500D02*
X107100D01*
X111833Y1469767D01*
Y1469667D01*
G01X87800Y1477500D02*
Y1477450D01*
X89500Y1475750D01*
X93500D01*
G01X87750Y1484000D02*
Y1477550D01*
X87800Y1477500D01*
G01X91300Y1488600D02*
X87750Y1485050D01*
Y1484000D01*
G01X104333Y1498167D02*
X108917D01*
X109000Y1498250D01*
G01D02*
X113000D01*
G01D02*
X117000D01*
G01D02*
X121000D01*
G01X129000D02*
X133000D01*
G01X125000D02*
X129000D01*
G01X121000Y1501750D02*
Y1506500D01*
G01X113000Y1501750D02*
Y1506500D01*
G01X117000Y1501750D02*
Y1506500D01*
G01X109000Y1501750D02*
Y1506500D01*
G01X129000Y1501750D02*
Y1506498D01*
X128999Y1506499D01*
G01X125000Y1501750D02*
Y1506500D01*
G01X113200Y1622800D02*
X111800D01*
X109252Y1620252D01*
Y1619703D01*
G01X113200Y1619300D02*
Y1617800D01*
X109252Y1613852D01*
Y1613297D01*
G01X148750Y568000D02*
X149300Y568550D01*
Y574400D01*
X149500Y574600D01*
G01X151170Y559250D02*
Y565580D01*
X148750Y568000D01*
G01X149500Y574600D02*
X149300Y574800D01*
Y578450D01*
X149500Y578650D01*
G01X149200Y559250D02*
Y564050D01*
X145250Y568000D01*
G01X145230Y571700D02*
X145696Y571234D01*
Y568446D01*
X145250Y568000D01*
G01X145300Y578750D02*
Y571770D01*
X145230Y571700D01*
G01X135200Y566400D02*
X135400Y566600D01*
X140400D01*
G01D02*
X143100D01*
X147230Y562470D01*
Y559250D01*
G01X155200Y679500D02*
X159900Y684200D01*
X173305D01*
X177200Y688095D01*
Y693050D01*
X175250Y695000D01*
Y701100D01*
G01X133000Y1447600D02*
X133100D01*
X138800Y1453300D01*
X140150D01*
G01X165494Y1437469D02*
Y1430344D01*
X165400Y1430250D01*
G01D02*
X165319Y1430331D01*
X160831D01*
G01X133799Y1440699D02*
X134248Y1440250D01*
X137500D01*
G01X143625Y1444750D02*
X141750D01*
X138000Y1448500D01*
G01X143625Y1444750D02*
X144500Y1445625D01*
Y1446769D01*
X149231Y1451500D01*
X152756D01*
X153456Y1452200D01*
X158012D01*
X160000Y1454188D01*
Y1455250D01*
X160750Y1456000D01*
Y1458000D01*
G01D02*
X166700D01*
X167000Y1457700D01*
G01X137500Y1443750D02*
Y1448000D01*
X138000Y1448500D01*
G01X157500Y1454800D02*
Y1457750D01*
X157250Y1458000D01*
G01X151375Y1444750D02*
X151500Y1444625D01*
Y1438500D01*
G01X160500Y1462500D02*
Y1461250D01*
X157250Y1458000D01*
G01X142569Y1429769D02*
X144969D01*
X151500Y1436300D01*
Y1438500D01*
G01X142400Y1499900D02*
X140800Y1498300D01*
X137050D01*
X137000Y1498250D01*
G01X133000D02*
X137000D01*
G01X133000Y1501750D02*
Y1505500D01*
G01X135008Y1508245D02*
X136255D01*
X137000Y1507500D01*
Y1501750D01*
G01X141300Y1625000D02*
X141100D01*
X137752Y1621652D01*
Y1619703D01*
G01X165252D02*
X166703D01*
X169876Y1622876D01*
Y1626303D01*
G01X141500Y1621600D02*
X141300Y1621400D01*
Y1617300D01*
X137752Y1613752D01*
Y1613297D01*
G01X173270Y1626517D02*
X173135D01*
X173000Y1626382D01*
Y1621797D01*
X165252Y1614049D01*
Y1613297D01*
X-222440Y19685D03*
Y1948818D03*
X29921Y24803D03*
Y111417D03*
Y458031D03*
Y544646D03*
Y717874D03*
Y804488D03*
X30000Y1164000D03*
X29921Y1250630D03*
Y1423858D03*
Y1510472D03*
Y1857086D03*
Y1943701D03*
X47244Y68110D03*
X80709Y119409D03*
Y139409D03*
Y329409D03*
Y309409D03*
X47244Y501338D03*
Y761181D03*
Y1207323D03*
Y1467165D03*
Y1900393D03*
X149606Y119409D03*
Y139409D03*
Y329409D03*
Y309409D03*
X643700Y19685D03*
Y1948818D03*
G54D20*
X19283Y310682D03*
X25900Y1725100D03*
X57400Y211300D03*
X56900Y240000D03*
X56600Y195000D03*
X32700Y256900D03*
X63000Y267700D03*
X39200Y347200D03*
X81400Y533900D03*
X78400Y591000D03*
X49600Y576900D03*
X61400Y676800D03*
X57400D03*
X64100Y912800D03*
X77002Y1137897D03*
X32900Y1664200D03*
X96100Y533900D03*
X124900Y588604D03*
X120800D03*
X93065Y597471D03*
X97265D03*
X92465Y610371D03*
X95200Y665700D03*
X110900Y884800D03*
X102600D03*
X119300D03*
X122529Y955744D03*
X117529D03*
X112529D03*
X100500Y1423700D03*
X91500D03*
X83500Y1465200D03*
X105000Y1423700D03*
X107500Y1490200D03*
X170600Y532500D03*
X155600Y532400D03*
X158000Y578600D03*
X170200Y627100D03*
X180365Y645771D03*
X137765Y662071D03*
X154500Y687200D03*
X149500Y711700D03*
X147900Y1003100D03*
X152100Y1003200D03*
X163500Y997700D03*
X159500D03*
X143800Y1003200D03*
X135000Y1411804D03*
X134700Y1404004D03*
X137500Y1443700D03*
G54D11*
X-181139Y20007D03*
X-180444Y1947256D03*
X150000Y64500D03*
X152500Y1906000D03*
X601704Y21248D03*
X602399Y1948497D03*
G54D21*
X29100Y321300D03*
X30100Y1083600D03*
X18600Y1644300D03*
X18400Y1720700D03*
X20200Y1692800D03*
X56900Y155300D03*
Y163300D03*
Y179300D03*
Y159300D03*
Y175300D03*
X46500Y213400D03*
X57800Y217000D03*
X56900Y199300D03*
X32800Y272300D03*
X70800Y431300D03*
X61000Y577200D03*
X78556Y690465D03*
X80700Y686400D03*
X45400Y916400D03*
X68700Y999800D03*
X49400Y1769800D03*
X88303Y61502D03*
X85800Y71500D03*
X117900Y437500D03*
X125956Y692165D03*
X125856Y688065D03*
Y683665D03*
X112900Y670600D03*
X83996Y848500D03*
Y844100D03*
Y852900D03*
X84000Y865700D03*
Y857200D03*
Y861500D03*
X111900Y1408200D03*
X91300Y1451000D03*
X109700Y1425900D03*
X91300Y1439000D03*
X84300Y1484000D03*
X128800Y1482000D03*
X159900Y545600D03*
X162700Y622700D03*
X152329Y615065D03*
X171800Y701100D03*
X152096Y1415000D03*
X140500Y1458400D03*
X152100Y1423400D03*
X152096Y1419200D03*
X190800Y439500D03*
G54D30*
X28000Y1769900D03*
X75700Y71500D03*
X58200Y662300D03*
Y657600D03*
X48700Y1764700D03*
X110200Y769100D03*
Y764100D03*
X99700Y1058400D03*
Y1053700D03*
X182300Y1652700D03*
Y1648000D03*
X141847Y1878698D03*
X141800Y1883700D03*
G54D12*
X8594Y6500D03*
X20000Y6000D03*
X17000Y36500D03*
X5594Y87000D03*
Y53500D03*
X29500Y53000D03*
X26000Y87000D03*
X30800Y130300D03*
X4594Y120500D03*
X23500Y124000D03*
X15000Y131500D03*
X14500Y100500D03*
Y112500D03*
X4500Y105500D03*
X5000Y137500D03*
X22500Y190000D03*
X29700Y191400D03*
X5594Y153500D03*
X4594Y187500D03*
X16500Y175000D03*
X15500Y143500D03*
X27000Y182000D03*
X14000Y184000D03*
X4500Y170500D03*
X21500Y241500D03*
X4594Y234000D03*
X24000Y212000D03*
X29000Y200500D03*
X13500Y230500D03*
X13000Y212500D03*
X5000Y221000D03*
X12500Y197500D03*
X4500Y202500D03*
X28050Y256950D03*
X18600Y249100D03*
X5094Y278000D03*
X6094Y257000D03*
X13500Y279000D03*
X13000Y244000D03*
X12500Y266500D03*
X5500Y269500D03*
X5000Y247500D03*
X19721Y267203D03*
X27900Y269471D03*
X5594Y312000D03*
X5304Y342500D03*
X4900Y328000D03*
X13500Y303500D03*
X13000Y321000D03*
X13500Y295000D03*
X5500Y295500D03*
X20010Y302982D03*
X6500Y375000D03*
X27000Y371000D03*
X4800Y356200D03*
X23700Y363900D03*
X29500Y364500D03*
X27000Y377500D03*
Y384000D03*
Y389500D03*
X4594Y421000D03*
X5304Y444500D03*
Y440500D03*
X5000Y408500D03*
X5304Y434500D03*
X4594Y396500D03*
X26500Y440000D03*
X26000Y432500D03*
X23800Y410700D03*
X5094Y469500D03*
X5000Y495000D03*
X4700Y458200D03*
X5000Y486500D03*
X11000Y578000D03*
X27300Y593000D03*
X5094Y600000D03*
X13510Y597990D03*
X27100Y578100D03*
X14000Y614000D03*
X4594Y625000D03*
X18000Y608000D03*
X6000Y612000D03*
Y646000D03*
X26000Y656500D03*
X5594Y688500D03*
X5304Y661000D03*
X14000Y659000D03*
X23000Y677500D03*
X8000Y678000D03*
X31000Y700500D03*
X20000Y696000D03*
X6000Y698000D03*
X28000Y706000D03*
X31000Y747000D03*
X22000Y746000D03*
X27000Y750000D03*
X26000Y732000D03*
X18000Y724000D03*
Y732500D03*
Y712000D03*
X6000Y706500D03*
Y722000D03*
Y730500D03*
X5594Y778000D03*
X6500Y799000D03*
X9500Y804000D03*
X24000Y756000D03*
X30000Y782000D03*
X16100Y794600D03*
X5594Y844500D03*
X6094Y819500D03*
X30500D03*
X10000Y811500D03*
X24000Y846000D03*
X24500Y853500D03*
X16000Y828000D03*
Y814000D03*
Y856000D03*
Y842000D03*
X4500Y833500D03*
X26053Y828247D03*
X5094Y897500D03*
X5594Y869000D03*
X16000Y906000D03*
X18000Y884000D03*
Y870000D03*
X4500Y857500D03*
X5000Y883500D03*
X18500Y896500D03*
X23053Y861247D03*
X5304Y926000D03*
X4594Y954000D03*
X18000Y934000D03*
Y920000D03*
X16000Y948000D03*
X4500Y913000D03*
Y941500D03*
X26053Y938247D03*
X5594Y984500D03*
X28000Y992000D03*
X16000Y962000D03*
Y990000D03*
Y976000D03*
Y1000000D03*
X4500Y970000D03*
Y997000D03*
X25053Y971247D03*
X4594Y1041500D03*
Y1013500D03*
X6000Y1058000D03*
X26000Y1010000D03*
X16000Y1014000D03*
Y1046000D03*
Y1032000D03*
X14000Y1060000D03*
X4500Y1029500D03*
X27553Y1029247D03*
X5094Y1074500D03*
X28000Y1072000D03*
X14000Y1074000D03*
Y1100000D03*
Y1086000D03*
X16000Y1110000D03*
X6000Y1096000D03*
X26100Y1088600D03*
X27218Y1097000D03*
X24500Y1102000D03*
X16000Y1124000D03*
Y1148000D03*
Y1134000D03*
Y1162000D03*
X6000Y1138000D03*
Y1118000D03*
Y1152000D03*
X26600Y1132400D03*
X24553Y1153247D03*
X5304Y1208000D03*
X4594Y1169500D03*
X24000Y1180000D03*
X16000Y1176000D03*
X8500Y1237000D03*
X30000Y1240000D03*
X16000Y1262000D03*
Y1244000D03*
X6000Y1252000D03*
X22000Y1232000D03*
X6500Y1302000D03*
X5094Y1268500D03*
X17700Y1283000D03*
X12000Y1274000D03*
Y1294000D03*
X28000Y1266000D03*
Y1286000D03*
Y1300000D03*
X19800Y1315400D03*
X13500Y1365000D03*
X6000Y1318000D03*
X28000Y1320000D03*
X30800Y1403900D03*
X5304Y1409400D03*
X4594Y1382000D03*
X7500Y1376500D03*
X8000Y1368000D03*
X4800Y1460700D03*
X4594Y1435500D03*
X5304Y1504100D03*
X4600Y1484800D03*
X29500Y1495800D03*
X5304Y1540500D03*
Y1522100D03*
X26600Y1570100D03*
X26900Y1547900D03*
Y1559100D03*
X4594Y1607500D03*
X5304Y1576200D03*
X26700Y1579800D03*
X7500Y1640200D03*
X5304Y1659000D03*
X4594Y1632000D03*
X29000Y1671000D03*
X19250Y1663100D03*
X13900Y1706200D03*
X5304Y1723500D03*
X4900Y1708000D03*
X4594Y1691000D03*
X4700Y1676100D03*
X30000Y1731000D03*
X4594Y1775000D03*
Y1751000D03*
X12600Y1753800D03*
X13100Y1742600D03*
Y1728900D03*
X12900Y1765200D03*
X20056Y1774189D03*
X4594Y1826500D03*
X5900Y1814100D03*
X4594Y1799500D03*
X12600Y1792800D03*
X12500Y1782500D03*
X4594Y1878500D03*
X12800Y1863700D03*
X5000Y1864100D03*
X18600Y1871400D03*
X4594Y1850000D03*
X24200Y1836700D03*
X15000Y1854900D03*
X14500Y1842000D03*
X27500Y1874500D03*
X24800Y1926500D03*
X5094Y1921000D03*
X4594Y1902000D03*
X24500Y1884000D03*
X13100Y1933900D03*
X16100Y1950700D03*
X5094Y1944500D03*
X15500Y1942500D03*
X4500Y1936000D03*
X6500Y1962000D03*
X25000Y1962500D03*
X12500Y1959000D03*
X63594Y7000D03*
Y25500D03*
X40594Y6000D03*
X49000Y18500D03*
X43000Y27000D03*
X64000Y17000D03*
X53000Y5000D03*
X31500Y5500D03*
X51500Y53000D03*
X74000Y45000D03*
X64500Y40000D03*
X32000D03*
X43900Y137200D03*
X63098Y119103D03*
X52000Y115600D03*
X51700Y131700D03*
X34400Y95300D03*
X71000Y131859D03*
X37000Y124000D03*
X62598Y141103D03*
X51900Y145700D03*
X69000Y153000D03*
X73500Y146000D03*
X60800Y147700D03*
X68000Y286000D03*
Y296000D03*
Y320000D03*
Y312000D03*
X76000Y296000D03*
X68000Y304000D03*
X36200Y318700D03*
X63200Y385100D03*
X74000Y390000D03*
X66000D03*
X58000D03*
X64000Y446500D03*
X62400Y430600D03*
X62900Y412900D03*
X61700Y421900D03*
X74000Y408000D03*
X66000D03*
Y418000D03*
X74000D03*
X73700Y423000D03*
X66000Y426000D03*
X58000D03*
X74000Y400000D03*
X66000D03*
X58000D03*
Y408000D03*
Y417500D03*
X58100Y431900D03*
X63096Y434540D03*
X68500Y434300D03*
X81000Y410500D03*
X70900Y427200D03*
X82000Y483600D03*
X46000Y490500D03*
X50100Y493000D03*
X42500D03*
X78200Y481700D03*
X63300Y464400D03*
X64000Y451000D03*
Y455500D03*
Y460000D03*
X62500Y472900D03*
X62600Y468500D03*
X62500Y477000D03*
X66000Y510500D03*
X78500Y506700D03*
X78200Y501000D03*
X71800Y506900D03*
X71900Y501000D03*
X72100Y521800D03*
X79400D03*
X72000Y514800D03*
X78000D03*
X51700Y522500D03*
X74942Y530983D03*
X77400Y536300D03*
X72500Y595900D03*
X56800Y576950D03*
X34100Y566600D03*
X36000Y554000D03*
X79122Y565700D03*
X79458Y578758D03*
X69800Y574200D03*
X70400Y565500D03*
X49665Y642933D03*
X43337Y650145D03*
X37000Y605000D03*
X80900Y668400D03*
X56710Y681069D03*
X40000Y659000D03*
X43281Y674991D03*
X39096Y674917D03*
X69100Y698006D03*
X71800Y701300D03*
X74100Y669398D03*
X32000Y666000D03*
X57200Y667884D03*
X50000Y712500D03*
Y749000D03*
X40000Y746500D03*
X36000Y730000D03*
X46000Y726000D03*
X65000Y775000D03*
Y766000D03*
X44000Y782000D03*
X42000Y802000D03*
Y788000D03*
X47600Y796800D03*
X81500Y837500D03*
X82000Y806500D03*
X48000Y816000D03*
X38000Y834000D03*
Y820000D03*
X46000Y848000D03*
Y834000D03*
X32000Y844000D03*
X78300Y832600D03*
X77600Y849100D03*
X48100Y853400D03*
X45600Y827500D03*
X43100Y866100D03*
X37500Y907500D03*
X77000Y871500D03*
X79000Y857000D03*
X62500Y862000D03*
X61500Y876500D03*
X78000Y878500D03*
X32000Y858000D03*
Y886000D03*
Y872000D03*
X77500Y907000D03*
X78300Y893900D03*
X77000Y863000D03*
X47000Y877600D03*
X40900Y901500D03*
X76500Y900500D03*
X65900Y900000D03*
X64100Y904800D03*
X41000Y931899D03*
X37500Y912000D03*
X34000Y944000D03*
Y934500D03*
X33500Y953000D03*
X61500Y938500D03*
X81500Y940000D03*
X75500Y936500D03*
X69500Y939000D03*
X55500Y955500D03*
X56500Y940000D03*
X62500Y924500D03*
X70000Y914500D03*
Y925500D03*
X76500Y927000D03*
X77500Y917000D03*
X64000Y980500D03*
X33500Y962500D03*
X34000Y984000D03*
Y974500D03*
Y1008000D03*
X55500Y968000D03*
X76400Y999100D03*
X37700Y991600D03*
X73000Y966000D03*
X66900Y969100D03*
X60000Y966800D03*
X81500Y985900D03*
X51500Y974100D03*
X31600Y1024300D03*
X33600Y1029900D03*
X34000Y1017500D03*
X39300Y1105800D03*
X34000Y1102000D03*
Y1072000D03*
X33550Y1080100D03*
X37200Y1091700D03*
X67302Y1133490D03*
X78292Y1148041D03*
X52100Y1132700D03*
X66000Y1149500D03*
X79044Y1144112D03*
X37500Y1118900D03*
X74000Y1132000D03*
X34000Y1144000D03*
X40000Y1136000D03*
Y1156000D03*
X32000Y1114000D03*
X77293Y1129729D03*
X64500Y1165700D03*
X58000Y1206000D03*
X60000Y1194000D03*
X61000Y1173000D03*
X54000Y1184000D03*
X44000Y1194000D03*
X71000Y1232600D03*
X42000Y1242000D03*
X50000Y1244000D03*
X58000Y1250000D03*
X46000Y1218000D03*
X31500Y1222000D03*
X58000D03*
X39500Y1231000D03*
X51800Y1231600D03*
X50100Y1261500D03*
X42000Y1266000D03*
Y1290000D03*
X34000Y1312000D03*
X40000Y1278000D03*
Y1298000D03*
X44000Y1306000D03*
X58000Y1312000D03*
Y1292000D03*
Y1272000D03*
X52000Y1296300D03*
X61000Y1363500D03*
X38000Y1334000D03*
X50000Y1318000D03*
X44000Y1326000D03*
Y1340000D03*
X54000Y1330000D03*
X72000Y1360000D03*
X31500Y1397500D03*
X81500Y1382000D03*
Y1416500D03*
Y1404000D03*
X52500Y1368500D03*
X71800Y1373900D03*
X70500Y1378500D03*
X69400Y1402900D03*
X39500Y1407900D03*
X55600Y1381700D03*
X48900Y1390500D03*
X60900D03*
X56700Y1400100D03*
X68800Y1417800D03*
X58800Y1412400D03*
X49000Y1413300D03*
X72900Y1393600D03*
X74900Y1408800D03*
X32000Y1391500D03*
X61500Y1380000D03*
X70400Y1444500D03*
X79000Y1436400D03*
X76200Y1430700D03*
X60600Y1423600D03*
X75600Y1420300D03*
X66500Y1433500D03*
X53100Y1430700D03*
X42600Y1444200D03*
X34000Y1465900D03*
X49100Y1448400D03*
X68500Y1454600D03*
X74500Y1461800D03*
X72300Y1469800D03*
X59000Y1444500D03*
X77000Y1449000D03*
X58100Y1459300D03*
X53500Y1519000D03*
X72000Y1514000D03*
X58500Y1519000D03*
X63000Y1482300D03*
X42700Y1500000D03*
X72700Y1480500D03*
X46500Y1484900D03*
X64100Y1495400D03*
X73000Y1491200D03*
X43300Y1518500D03*
X49500Y1505000D03*
X59000Y1472000D03*
X34000Y1477600D03*
X57000Y1568500D03*
X57500Y1562000D03*
X59500Y1541000D03*
X54300Y1541200D03*
X80000Y1531600D03*
X73900Y1535900D03*
X46600Y1541100D03*
X45300Y1563600D03*
X45900Y1532800D03*
X45400Y1523800D03*
X37900Y1570000D03*
X38800Y1541700D03*
X38300Y1561800D03*
X54500Y1574000D03*
X33000Y1575000D03*
X44400Y1592100D03*
X33100Y1587400D03*
X38300Y1579600D03*
X53300Y1609200D03*
X64400Y1605900D03*
X71600Y1607700D03*
X50600Y1589300D03*
Y1582800D03*
Y1595300D03*
Y1601300D03*
X55300Y1601100D03*
Y1595100D03*
Y1582600D03*
Y1589100D03*
X68700Y1603900D03*
X55400Y1613300D03*
X58500Y1607700D03*
X43200Y1634800D03*
X62300Y1641300D03*
X59500Y1627500D03*
Y1667000D03*
X70000Y1668000D03*
X76000Y1646000D03*
Y1634000D03*
X75500Y1659500D03*
X54000Y1646500D03*
X64500Y1646000D03*
X55000Y1634000D03*
X64000D03*
X64500Y1658500D03*
X53500Y1659000D03*
X32900Y1656300D03*
X42500Y1699500D03*
X44600Y1724400D03*
X44900Y1706800D03*
X61500Y1716500D03*
X56000Y1695000D03*
Y1704500D03*
Y1712500D03*
X55500Y1723500D03*
X69000Y1684500D03*
X80500D03*
X62500Y1691500D03*
X65000Y1724000D03*
X62500Y1709000D03*
X72500Y1717000D03*
Y1699000D03*
X75500Y1679000D03*
X62500Y1700000D03*
X33000Y1718500D03*
X32949Y1709451D03*
X38800Y1775000D03*
X41600Y1746900D03*
X48400D03*
X53000Y1750500D03*
X36700Y1764700D03*
X56500Y1769300D03*
X44900Y1740300D03*
X64500Y1758500D03*
X55500Y1735500D03*
X65000Y1735000D03*
X79000Y1766500D03*
X65000Y1749000D03*
Y1768000D03*
Y1742500D03*
X71500Y1760000D03*
X72500Y1733000D03*
X60000Y1730000D03*
X42000Y1784400D03*
X44400Y1821400D03*
X81000Y1802000D03*
X73000Y1813000D03*
X64500Y1821500D03*
Y1812000D03*
Y1801500D03*
X65000Y1790000D03*
X72000Y1798000D03*
X57000Y1805500D03*
X39179Y1792306D03*
X39700Y1869700D03*
X46700Y1857700D03*
X46500Y1850200D03*
X44500Y1833500D03*
X39700Y1846600D03*
X45500Y1865000D03*
X31500Y1878500D03*
X36000Y1835500D03*
X75500Y1838500D03*
X63500Y1863000D03*
Y1856000D03*
X64000Y1844500D03*
Y1834000D03*
X73000Y1847000D03*
X72500Y1830000D03*
X66000Y1917000D03*
X54500Y1889500D03*
X63500Y1928000D03*
X61500Y1922500D03*
X46000Y1923000D03*
X54000Y1928500D03*
X35300Y1925300D03*
X36500Y1900500D03*
X63500Y1963000D03*
X63594Y1935500D03*
X61600Y1954700D03*
X34500Y1963200D03*
X41100Y1957500D03*
X55300Y1959100D03*
X45100Y1933400D03*
X35000Y1933500D03*
X43500Y1945000D03*
X49053Y1951747D03*
X128500Y89000D03*
X118000Y54500D03*
X124000Y74500D03*
X105000Y55000D03*
X85000Y45000D03*
X105000D03*
X95000D03*
X115000D03*
X125000D03*
X127700Y119200D03*
X128700Y104200D03*
X131000Y138100D03*
X118000Y124500D03*
X119000Y109500D03*
X95000Y125000D03*
X105000D03*
X95000Y134000D03*
X86000Y152000D03*
X129000Y160100D03*
X131000Y150100D03*
X118000Y154500D03*
Y142500D03*
X95000Y143000D03*
X105000D03*
X95000Y155000D03*
X105000D03*
X131800Y289700D03*
X130900Y259100D03*
X102000Y312000D03*
X104000Y304000D03*
X94000D03*
Y312000D03*
Y320000D03*
X114000Y296000D03*
X106000D03*
X96000D03*
X86000D03*
X111500Y390000D03*
X101300Y390100D03*
X105500Y390000D03*
X118000Y396000D03*
Y386000D03*
X105500Y406500D03*
X101500D03*
X107000Y426500D03*
X98000D03*
X102500D03*
X111200Y426400D03*
X110500Y406500D03*
X118500Y442000D03*
X89800Y446000D03*
X131000Y447000D03*
X91900Y410500D03*
X84500Y433000D03*
X88500Y426500D03*
X86400Y410500D03*
X122500Y429000D03*
X125100Y408900D03*
X118000Y424000D03*
Y404000D03*
X130000Y432000D03*
X118000Y414000D03*
X115000Y486100D03*
X129000Y485500D03*
X120000D03*
X110800Y482600D03*
X99800Y482000D03*
X110800Y488600D03*
X100000Y488000D03*
Y494000D03*
X110800Y494600D03*
X129000Y493500D03*
X120000D03*
X106500Y469500D03*
X115500Y476700D03*
X122500Y450500D03*
Y457500D03*
Y463500D03*
X121500Y475500D03*
X122500Y469500D03*
X117000Y455000D03*
Y460500D03*
Y466000D03*
Y471500D03*
Y449000D03*
X89800Y452900D03*
Y459000D03*
X111500Y473000D03*
X99500D03*
X89800Y464800D03*
X130500Y454000D03*
Y461000D03*
Y468000D03*
Y474500D03*
X120000Y501500D03*
X129000Y517500D03*
X100000Y512000D03*
X110800Y500600D03*
X100000Y500000D03*
X85000Y506400D03*
X84500Y514400D03*
X129000Y501500D03*
Y509500D03*
X110800Y512600D03*
X120000Y517500D03*
X100000Y506000D03*
X110800Y506600D03*
X120000Y509500D03*
Y523500D03*
X129000D03*
X100000Y519100D03*
X117000Y530000D03*
X96900Y541600D03*
X99800Y545600D03*
X120800Y598700D03*
X103100Y587600D03*
X87595Y581300D03*
X112018Y584900D03*
X106338Y580496D03*
X118565Y592846D03*
X83619Y581742D03*
X82900Y574500D03*
X101800Y557400D03*
X96500Y567600D03*
X90630Y602020D03*
X99578Y605771D03*
X93063Y629134D03*
X94545Y601197D03*
X91463Y623143D03*
X86443Y662853D03*
X88967Y659749D03*
X84504Y666353D03*
X90674Y663367D03*
X121500Y683500D03*
X119576Y687008D03*
X120702Y690847D03*
X100600Y670600D03*
X112800Y653500D03*
X108200Y655825D03*
X122088Y665912D03*
X119300Y656600D03*
X111400Y658500D03*
X119000Y673300D03*
X87310Y676796D03*
X124800Y696600D03*
X129800Y696800D03*
X98000Y674327D03*
X102913Y673973D03*
X107113Y674001D03*
X108500Y695500D03*
X103500D03*
X99001Y694866D03*
X86060Y695200D03*
X86000Y689900D03*
X125202Y657500D03*
X129000Y653600D03*
X95500Y728000D03*
X105500Y732000D03*
X125000Y734000D03*
X116500Y752000D03*
X125000Y751000D03*
X125500Y741500D03*
X130000Y736500D03*
X120500Y732500D03*
X120000Y717500D03*
X115000Y704500D03*
X117500Y724500D03*
X106882Y794201D03*
X107000Y798200D03*
Y802400D03*
X123000Y800000D03*
X122500Y792500D03*
X114000Y800000D03*
X113500Y792500D03*
X130000Y800000D03*
X129500Y792500D03*
X121500Y783500D03*
X121000Y776000D03*
X129500Y782000D03*
X129000Y774500D03*
X125000Y758500D03*
X115200Y784200D03*
X115000Y773200D03*
X121000Y767900D03*
X109000Y809500D03*
X95500Y841500D03*
X82500Y814000D03*
X123500Y842500D03*
Y816000D03*
X123000Y808500D03*
X115000Y813000D03*
X114500Y805500D03*
X129200Y830400D03*
X129800Y813500D03*
X124500Y825100D03*
X90500Y831500D03*
X87000Y839500D03*
X119300Y837000D03*
X92400Y848900D03*
X103400Y838300D03*
X85500Y903000D03*
X116053Y903247D03*
X127000Y903000D03*
X90000Y893000D03*
X102500Y893500D03*
X117500Y893000D03*
X125000Y868500D03*
X124500Y858000D03*
X107000Y903000D03*
X124500Y876500D03*
X126000Y892500D03*
X96053Y903247D03*
X83400Y878600D03*
X98700Y877100D03*
X92800Y865300D03*
X111100Y876700D03*
X92700Y858100D03*
X108200Y953500D03*
X112984Y946835D03*
X120054Y945600D03*
X125500Y944000D03*
X105000Y958000D03*
X86500Y932000D03*
X96500Y916500D03*
X107000Y918000D03*
X115000Y920000D03*
X125500D03*
X126000Y930000D03*
X115500D03*
X99000Y953000D03*
X88500Y940500D03*
X120000Y916000D03*
X124000Y909000D03*
X113500Y909500D03*
X103500D03*
X94000Y910500D03*
X85500Y915000D03*
X126000Y954000D03*
X110000Y949500D03*
X117529Y948844D03*
X93000Y925500D03*
X130903Y958178D03*
X94500Y950500D03*
X125000Y967000D03*
X130500Y966000D03*
X124000Y971500D03*
X117000Y1008500D03*
X105500Y996000D03*
X95500Y999000D03*
X87000Y997500D03*
X106500Y1008500D03*
X119000Y975000D03*
X108500Y964000D03*
Y971000D03*
X114800Y1005000D03*
X124618Y959244D03*
X110400Y997850D03*
X119080Y992900D03*
X127700Y998400D03*
X87600Y965900D03*
X90542Y987958D03*
X97958Y966958D03*
X103500Y966500D03*
X130900Y1003400D03*
X91500Y1030500D03*
X97250Y1023500D03*
X85500Y1009500D03*
X110500Y1041500D03*
X111500Y1030000D03*
Y1020000D03*
X104000Y1014000D03*
X110500Y1051000D03*
X103500Y1042000D03*
Y1028500D03*
X116500Y1049000D03*
Y1035500D03*
X117500Y1023500D03*
X95400Y1064100D03*
X91400D03*
X87000Y1063000D03*
X128500Y1076800D03*
X120000Y1108000D03*
Y1102000D03*
X115000Y1108500D03*
X110500Y1064500D03*
Y1112000D03*
X103500Y1073500D03*
X104500Y1095000D03*
X116500Y1076000D03*
X109000Y1083500D03*
X116500Y1062500D03*
X89000Y1167400D03*
X118500Y1166000D03*
X105000Y1196000D03*
X119300Y1191400D03*
X119500Y1177500D03*
Y1205500D03*
X104500Y1208000D03*
X94000Y1189000D03*
X91500Y1200000D03*
X99000Y1265500D03*
X117500Y1251000D03*
X112000Y1250500D03*
Y1244500D03*
X119300Y1245400D03*
Y1219400D03*
X119500Y1231500D03*
X104500Y1219500D03*
X92000Y1254000D03*
X103500Y1229000D03*
X92000Y1241500D03*
X103000Y1244900D03*
X92000Y1214500D03*
X91500Y1229000D03*
X119000Y1269000D03*
X99500Y1310000D03*
Y1294000D03*
X98000Y1282000D03*
X123800Y1283900D03*
X124000Y1270000D03*
X113800Y1287900D03*
X114000Y1274000D03*
X123800Y1311900D03*
X124000Y1298000D03*
X92000Y1295500D03*
X91500Y1314500D03*
X114500Y1296500D03*
X97800Y1327900D03*
X123800Y1337900D03*
X124000Y1324000D03*
X113800Y1331900D03*
X114000Y1318000D03*
X115800Y1363900D03*
X116000Y1350000D03*
X123800Y1365900D03*
X124000Y1352000D03*
X83800Y1365900D03*
X84000Y1352000D03*
X93800Y1353900D03*
X94000Y1340000D03*
Y1366000D03*
X90800Y1331200D03*
X105500Y1415000D03*
X99600Y1416500D03*
X100500Y1384500D03*
Y1389000D03*
X124000Y1376500D03*
X114000Y1376000D03*
X114500Y1370500D03*
X83800Y1391900D03*
X93800Y1379900D03*
Y1393200D03*
X93600Y1407100D03*
X97500Y1412000D03*
X89700Y1409700D03*
X110000Y1418000D03*
X122862Y1385500D03*
X129000Y1416425D03*
X99500Y1407500D03*
X100000Y1443000D03*
X101000Y1460750D03*
X86900Y1451000D03*
X126600Y1461500D03*
X132200Y1424800D03*
X94000Y1427800D03*
X87200Y1431900D03*
X87700Y1446500D03*
X87300Y1436000D03*
X95500Y1468000D03*
X113024Y1452079D03*
X117122Y1448001D03*
X117195Y1456070D03*
X121338Y1452021D03*
X117024Y1452000D03*
X100200Y1433800D03*
X83500Y1469500D03*
X87200Y1440000D03*
X99800Y1455600D03*
X99700Y1450700D03*
X109500Y1438000D03*
X98500Y1428400D03*
X103000Y1429500D03*
X123000Y1431300D03*
X126975Y1435400D03*
X127300Y1468800D03*
X117000Y1435200D03*
X111833Y1469667D03*
X117500Y1519500D03*
X94000Y1514000D03*
X93000Y1518700D03*
X85200Y1515000D03*
X91300Y1488600D03*
X97000Y1503100D03*
X93500Y1482700D03*
X99170Y1485790D03*
X103700Y1470300D03*
X85000Y1490000D03*
X104333Y1498167D03*
X130180Y1486680D03*
X98000Y1564700D03*
X124500Y1524000D03*
X87900Y1523400D03*
X94000Y1562000D03*
Y1550000D03*
X119000Y1529500D03*
X129000Y1562500D03*
X128000Y1568000D03*
X114000Y1546000D03*
X129000Y1542500D03*
X122000Y1546000D03*
Y1538000D03*
X129000Y1549000D03*
X94000Y1556000D03*
X129000Y1535000D03*
X115900Y1569700D03*
X94000Y1568000D03*
X102000D03*
Y1556000D03*
Y1550000D03*
Y1562000D03*
Y1544000D03*
X114000Y1564000D03*
X121800Y1569929D03*
X122000Y1564000D03*
X114000Y1558000D03*
X122000Y1552000D03*
X114000D03*
X122000Y1558000D03*
X111500Y1537500D03*
X129000Y1555500D03*
X116000Y1576000D03*
X122000D03*
X89500Y1610000D03*
X120500Y1606000D03*
X122000Y1584000D03*
X116000D03*
Y1592000D03*
X122000D03*
X116000Y1600000D03*
X122000Y1612000D03*
X104000Y1605500D03*
X116000Y1612000D03*
X122000Y1600000D03*
X128000Y1606000D03*
X94500Y1605500D03*
X113500D03*
X117500Y1669000D03*
X127500D03*
X86000D03*
X97000D03*
X107000D03*
X127000Y1646000D03*
X118000D03*
X117000Y1633500D03*
X127500Y1633000D03*
Y1659500D03*
X117500D03*
X108000Y1646000D03*
X106000Y1634000D03*
X107000Y1659500D03*
X96000Y1646000D03*
X96500Y1634000D03*
X97000Y1659500D03*
X86000Y1646000D03*
Y1634000D03*
Y1659500D03*
X122000Y1685500D03*
X91000Y1685000D03*
X103000D03*
X112500D03*
X98500Y1717000D03*
Y1696500D03*
X99000Y1707000D03*
X117500Y1679000D03*
X125000D03*
X86000D03*
X97500Y1679500D03*
X107500Y1679000D03*
X109500Y1719500D03*
X110000Y1709500D03*
X109500Y1699000D03*
X119500Y1710110D03*
Y1696610D03*
X86500Y1713610D03*
Y1700110D03*
X119500Y1725110D03*
X111500Y1768500D03*
X108500Y1727000D03*
X117500Y1732000D03*
X119500Y1760000D03*
X97500Y1775500D03*
X86500Y1726000D03*
X87000Y1774110D03*
X119500Y1747110D03*
X110500Y1801000D03*
X88500Y1785000D03*
X97500Y1796000D03*
X98000Y1786000D03*
X86500Y1793110D03*
X108268Y1777300D03*
X107768Y1789110D03*
X120000Y1811500D03*
X119500Y1796500D03*
X84000Y1869600D03*
X114000Y1843500D03*
X97000Y1850500D03*
X99500Y1862500D03*
X106500D03*
X114500D03*
X122500D03*
X120500Y1836500D03*
Y1850500D03*
X108500Y1851610D03*
X85100Y1844500D03*
X85700Y1852300D03*
X132000Y1892000D03*
X124500Y1892403D03*
X116948Y1892000D03*
X82000Y1915000D03*
X118000Y1922000D03*
X184000Y55500D03*
X174000D03*
X164000D03*
X154000Y75500D03*
X135000Y50000D03*
Y70000D03*
Y45000D03*
X145000D03*
X155000D03*
X165000D03*
X175000D03*
X137200Y123600D03*
X180500Y112000D03*
X167000Y130500D03*
X176000Y131000D03*
X167000Y93000D03*
X153000Y90500D03*
X171500Y105500D03*
X170500Y120500D03*
X146500Y131859D03*
X154000Y105500D03*
X147600Y150900D03*
X165300Y145200D03*
X137900Y171400D03*
X174500Y143500D03*
X173500Y151500D03*
X138800Y162100D03*
X142000Y291000D03*
X141300Y298100D03*
X143400Y318700D03*
X174000Y316000D03*
X164000D03*
X182000Y296000D03*
X172000D03*
X162000D03*
X172000Y310000D03*
X182000D03*
X184000Y303000D03*
X176000Y302000D03*
X166000D03*
X143300Y343400D03*
X151300Y298200D03*
X181800Y369000D03*
X181100Y364050D03*
X180850Y348800D03*
X150000Y386000D03*
X134000Y396000D03*
X150000D03*
X134000Y386000D03*
X162612Y438169D03*
X161600Y445900D03*
X136000Y447000D03*
X143400Y408200D03*
X134000Y404500D03*
X174500Y432000D03*
X162000D03*
X145500Y427000D03*
X142000Y432000D03*
X134000Y414000D03*
X150000Y404000D03*
Y414000D03*
X134000Y424000D03*
X150000D03*
X169200Y482800D03*
X144000Y493500D03*
Y486182D03*
X137000Y493000D03*
X136500Y485500D03*
X144400Y470800D03*
X161900Y451600D03*
X162000Y457600D03*
X161900Y463300D03*
X135500Y454000D03*
Y461000D03*
Y474500D03*
Y468000D03*
X149000Y522500D03*
X173700Y513900D03*
X144000Y517500D03*
Y501500D03*
X173500Y506000D03*
X173600Y498800D03*
X157100Y500000D03*
X137000Y510000D03*
X137500Y523500D03*
X174900Y523300D03*
X156800Y515400D03*
Y506900D03*
X137000Y501500D03*
X137500Y517500D03*
X144600Y533800D03*
X182600Y546900D03*
X174800Y532200D03*
X151500Y533000D03*
X164200Y541900D03*
X180500Y595000D03*
X171600Y595400D03*
X147500Y551500D03*
X141800Y559250D03*
X150500Y596000D03*
X153500Y574359D03*
X140700Y576600D03*
X149500Y574600D03*
X145230Y571700D03*
X135200Y566400D03*
X152700Y618803D03*
X170349Y619949D03*
X145500Y604000D03*
X175800Y617635D03*
X164950Y615700D03*
X180500Y627771D03*
X165600Y630269D03*
X176300Y608635D03*
X157200Y620800D03*
X146663Y634051D03*
X148595Y618300D03*
X151335Y640400D03*
X145200Y644600D03*
X163100Y604717D03*
X179017Y620013D03*
X151432Y661741D03*
X148995Y658568D03*
X174100Y652900D03*
X134100Y674500D03*
X176000Y679000D03*
Y665500D03*
X167300Y653800D03*
X162300Y659100D03*
X183500Y698000D03*
X165500Y677500D03*
X159700Y652000D03*
X153200Y653200D03*
X173000Y691000D03*
X142000Y701000D03*
X158500Y695000D03*
X145500Y675000D03*
X181000Y729000D03*
Y715500D03*
X182500Y745000D03*
X181500Y738500D03*
X169100Y722100D03*
X145000Y711750D03*
X167600Y703300D03*
X169000Y795500D03*
X178000Y797500D03*
X175000Y786500D03*
X182500Y758500D03*
X173500Y777500D03*
Y764000D03*
X172000Y757500D03*
X181700Y768400D03*
X165000Y786000D03*
X171500Y819500D03*
X163500Y805500D03*
X177500Y812000D03*
Y826500D03*
X140500Y846500D03*
X134500Y840500D03*
X145500Y885000D03*
X137500Y903000D03*
X146000Y893000D03*
X135000D03*
X134500Y885500D03*
X137500Y876500D03*
X145500Y856500D03*
X157500Y858000D03*
X156300Y877200D03*
X156500Y889000D03*
X160500Y916500D03*
X153500Y941000D03*
X141000Y938500D03*
X135000Y918000D03*
X135500Y927500D03*
X144000Y919500D03*
Y929000D03*
X143000Y910500D03*
X135500Y909000D03*
X154700Y909700D03*
X154500Y926500D03*
X182000Y950500D03*
X133500Y938000D03*
Y953000D03*
X139500Y951500D03*
X134000Y990500D03*
X136500Y967000D03*
X184000Y987500D03*
X135000Y975500D03*
X143100Y1007100D03*
X146800Y1018900D03*
X143900Y1022700D03*
X162000Y1027000D03*
X174000Y1012400D03*
X166300Y1021300D03*
X182500Y1041500D03*
X182000Y1029500D03*
Y1016000D03*
X171000Y1046000D03*
Y1032500D03*
X175000Y1059000D03*
X160500Y1053500D03*
X181000Y1051000D03*
X164700Y1033600D03*
X176000Y1018500D03*
X183500Y1065500D03*
X171000Y1068000D03*
X166000Y1080000D03*
X173000Y1082000D03*
X165000Y1097000D03*
X181000Y1098500D03*
X175000Y1072500D03*
X160500Y1067000D03*
X170000Y1103000D03*
Y1089500D03*
X157000Y1101500D03*
X159500Y1087500D03*
X181000Y1079500D03*
X154600Y1111000D03*
X158500Y1075800D03*
X158595Y1110789D03*
X155000Y1120000D03*
Y1125000D03*
Y1130500D03*
X181000Y1112500D03*
X177102Y1129800D03*
X171502Y1129547D03*
X147500Y1165500D03*
Y1186000D03*
X178644Y1202519D03*
X163344Y1181200D03*
X161500Y1227500D03*
X147500Y1221500D03*
X146500Y1241500D03*
X147000Y1265500D03*
X183500Y1241500D03*
X165000Y1264500D03*
X178500Y1268500D03*
X147500Y1288000D03*
Y1311000D03*
X164500Y1299500D03*
X147500Y1332000D03*
X147000Y1348000D03*
X147500Y1366500D03*
X147000Y1377000D03*
X146500Y1417619D03*
X159774Y1414374D03*
X148300Y1465000D03*
X137000Y1429200D03*
X173375Y1432500D03*
X149686Y1460007D03*
X133500Y1467100D03*
X136100Y1463900D03*
X152500Y1456000D03*
X134400Y1454300D03*
X133000Y1447600D03*
X133799Y1440699D03*
X165500Y1450600D03*
X138000Y1448500D03*
X174000Y1515500D03*
X174500Y1509500D03*
Y1503500D03*
X142400Y1499900D03*
X136500Y1481425D03*
X148500Y1479500D03*
X174000Y1522000D03*
X136000Y1528000D03*
X150000Y1570000D03*
X166898Y1567102D03*
X168500Y1526000D03*
X148000Y1564000D03*
X161300Y1563100D03*
X169500Y1561500D03*
X170000Y1548500D03*
X154000Y1564000D03*
X156000Y1570000D03*
X161400Y1543500D03*
X170000Y1555000D03*
X168500Y1533500D03*
X148000Y1542000D03*
Y1528000D03*
Y1558000D03*
X136000Y1548000D03*
Y1555000D03*
Y1562000D03*
Y1536000D03*
Y1542000D03*
Y1568000D03*
X170000Y1541000D03*
X148000Y1550000D03*
X156000Y1576000D03*
X150000D03*
X156000Y1582000D03*
X156500Y1591000D03*
X150500Y1582000D03*
Y1591000D03*
X172000Y1606000D03*
X182500Y1599400D03*
X146000Y1612000D03*
X148000Y1606000D03*
X182500Y1592000D03*
X164000Y1606000D03*
X156500Y1600000D03*
X156000Y1606000D03*
X150500Y1600000D03*
X138500Y1606000D03*
X182500Y1584500D03*
X141500Y1673000D03*
X136500Y1651000D03*
X176000Y1646000D03*
X166000D03*
X158000D03*
X148000D03*
X176000Y1632000D03*
X178000Y1659500D03*
X167500Y1632500D03*
X170000Y1659500D03*
X149000Y1632500D03*
X159000D03*
X138000Y1634000D03*
X137500Y1659500D03*
X159000D03*
X148500Y1660000D03*
X138000Y1646000D03*
X139000Y1696500D03*
Y1712500D03*
X181500Y1716500D03*
X158500D03*
X167500Y1716000D03*
X182000Y1704000D03*
X168500Y1705000D03*
X158500D03*
X163000Y1697000D03*
X174268Y1697110D03*
X152000D03*
Y1710610D03*
Y1725610D03*
X138500Y1727500D03*
X182000Y1726000D03*
X183600Y1765100D03*
X162500Y1773000D03*
X152500Y1771110D03*
X173268Y1776000D03*
X139000Y1800500D03*
X138000Y1824000D03*
X169000Y1781500D03*
X156500Y1782000D03*
X155500Y1798500D03*
X166500Y1798000D03*
X179000Y1798500D03*
X162000Y1790000D03*
X172768Y1790110D03*
X152000D03*
X137000Y1877500D03*
X139000Y1851000D03*
X138500Y1839500D03*
X161500Y1852500D03*
X183100Y1838300D03*
X160500Y1877500D03*
X173000Y1852610D03*
X151500Y1851110D03*
X139861Y1889461D03*
X161000Y1901500D03*
X194000Y55500D03*
X185000Y45000D03*
X195000D03*
X200000Y55000D03*
Y65000D03*
Y75000D03*
Y85000D03*
X187500Y130500D03*
X190500Y105000D03*
X189500Y120000D03*
X200000Y100000D03*
Y120000D03*
Y140000D03*
X191900Y167700D03*
X191700Y186500D03*
X186000Y143000D03*
X201089Y181700D03*
X197500Y151500D03*
X185500D03*
X191800Y234900D03*
Y221100D03*
X191600Y206900D03*
X201500Y208000D03*
X201000Y222500D03*
X200500Y235000D03*
Y195900D03*
X191900Y244600D03*
X202000Y274000D03*
Y254000D03*
X201089Y282600D03*
X202000Y264000D03*
X187500Y338000D03*
X202000Y340000D03*
Y328000D03*
Y295000D03*
X201089Y305500D03*
Y315500D03*
X184500Y325500D03*
X201500Y378000D03*
X202000Y366500D03*
Y353000D03*
X188500Y364100D03*
X188300Y368600D03*
X192600Y392600D03*
X201089Y388400D03*
X201500Y397500D03*
X200500Y437500D03*
X201000Y430500D03*
X201089Y407000D03*
X200000Y420500D03*
X192471Y397355D03*
X192400Y401900D03*
X186600Y425750D03*
X192300Y410950D03*
X192409Y417655D03*
X189928Y435800D03*
X197500Y481500D03*
X186500Y498000D03*
X192000Y490000D03*
Y498000D03*
X200300Y498100D03*
X199500Y489400D03*
X188500Y474500D03*
X189900Y467500D03*
Y460500D03*
X190400Y453500D03*
X195000Y467500D03*
X194500Y474500D03*
X195000Y460500D03*
X195500Y453500D03*
X190239Y447449D03*
X195600Y447500D03*
X186500Y513500D03*
Y506000D03*
X192000Y513500D03*
Y506000D03*
X190200Y523400D03*
X201089Y523500D03*
X186500Y519000D03*
X193600Y519100D03*
X200100Y513600D03*
X199800Y506000D03*
X201200Y519200D03*
X201500Y544500D03*
X201089Y529500D03*
X192400Y529400D03*
X191900Y538200D03*
X201500Y535000D03*
X192000Y543500D03*
X202000Y578000D03*
Y586000D03*
Y595000D03*
X193700D03*
X194400Y586000D03*
X201500Y552500D03*
X201089Y558000D03*
X201500Y564000D03*
X201089Y570600D03*
X190500Y550500D03*
X202000Y607500D03*
X196500Y641500D03*
X192600Y633000D03*
X201500Y621500D03*
X202000Y650500D03*
X194000Y628500D03*
Y615000D03*
X192500Y645000D03*
X195000Y670000D03*
X185000Y673500D03*
X188100Y689100D03*
X197500Y685000D03*
X202000Y676500D03*
X192500Y658500D03*
X191500Y692500D03*
X193100Y679000D03*
X184700Y663900D03*
X196000Y718500D03*
X184500Y708500D03*
X197000Y704000D03*
X195500Y739000D03*
X197500Y753000D03*
X202000Y710000D03*
Y740500D03*
X191500Y724000D03*
Y710500D03*
Y746500D03*
X196000Y789500D03*
X196500Y797000D03*
X187900Y785300D03*
X202000Y765000D03*
Y786000D03*
X191500Y760000D03*
X194500Y782500D03*
Y769000D03*
X196800Y828500D03*
X197000Y815000D03*
X190000Y823500D03*
X190500Y831000D03*
X202000Y807500D03*
X201500Y835500D03*
X192500Y853000D03*
Y839500D03*
X185000Y843500D03*
X184500Y879000D03*
Y865500D03*
X192000Y879000D03*
Y865500D03*
X194000Y907000D03*
Y893500D03*
X187000Y891000D03*
X192000Y934500D03*
Y921000D03*
Y948500D03*
X185000Y917500D03*
X192000Y962000D03*
X192500Y985500D03*
Y972000D03*
X195500Y1001000D03*
X190000Y1052000D03*
X195500Y1014500D03*
X193500Y1042500D03*
Y1029000D03*
X195000Y1086500D03*
X194500Y1100500D03*
X195000Y1074500D03*
Y1061000D03*
X201000Y1106500D03*
Y1093000D03*
X187500Y1103500D03*
Y1090000D03*
X186000Y1133000D03*
X191800Y1280900D03*
X189000Y1432000D03*
X194500Y1546000D03*
X193000Y1556500D03*
X197000Y1551500D03*
X195500Y1530500D03*
X193000Y1562500D03*
X189400Y1544100D03*
X187900Y1566600D03*
X189500Y1577000D03*
X198500Y1584000D03*
X192000Y1586000D03*
X197500Y1593000D03*
X191500Y1595000D03*
X199000Y1619500D03*
X190000Y1622000D03*
X198000Y1632500D03*
X191500Y1631000D03*
X198000Y1647500D03*
X196500Y1656000D03*
X197000Y1713000D03*
Y1691500D03*
X184500Y1696500D03*
X197500Y1776500D03*
Y1754000D03*
X197000Y1735500D03*
X185000Y1738500D03*
X198000Y1818500D03*
X196500Y1800500D03*
X185500Y1804500D03*
X186000Y1790000D03*
X197500Y1860000D03*
X197000Y1838500D03*
X194400Y1876700D03*
X185000Y1852500D03*
X201500Y1900500D03*
X190500Y1924000D03*
X201000Y1923000D03*
X195500Y1905000D03*
X196500Y1882000D03*
G54D22*
X22900Y397800D03*
Y418300D03*
X19100Y667000D03*
X81100Y398500D03*
X47700Y397800D03*
X81100Y419000D03*
X47700Y418300D03*
X43900Y667000D03*
X73600Y798400D03*
X63700Y1090600D03*
X36600Y1551500D03*
X61400D03*
X113100Y88500D03*
X105900Y398500D03*
Y419000D03*
X98400Y798400D03*
X88500Y1090600D03*
X137900Y88500D03*
X185300Y397900D03*
X160500D03*
X185200Y356700D03*
X160400D03*
X185400Y376900D03*
X160600D03*
X185300Y418400D03*
X160500D03*
X184900Y1531500D03*
X160100D03*
X185000Y1551600D03*
X160200D03*
G54D31*
X21350Y1781000D03*
X77953Y54502D03*
X71650Y584000D03*
X58350D03*
X45050Y593000D03*
X58350D03*
X81850Y715400D03*
X81350Y740400D03*
X60150Y1011800D03*
X73450D03*
X64450Y1032100D03*
X77750D03*
X34650Y1781000D03*
X91253Y54502D03*
X95850Y68500D03*
X109150D03*
X95150Y715400D03*
X94650Y740400D03*
G54D40*
X71802Y52947D03*
X71400Y68154D03*
X75200Y737900D03*
X75700Y715500D03*
X53800Y1009500D03*
X103500Y593900D03*
X146365Y607721D03*
G54D13*
X15906Y48110D03*
Y58110D03*
Y68110D03*
Y78110D03*
Y88110D03*
Y481339D03*
Y491339D03*
Y501339D03*
Y511339D03*
Y521339D03*
Y741181D03*
Y751181D03*
Y761181D03*
Y771181D03*
Y781181D03*
Y1187323D03*
Y1197323D03*
Y1207323D03*
Y1217323D03*
Y1227323D03*
Y1447165D03*
Y1457165D03*
Y1467165D03*
Y1477165D03*
Y1487165D03*
Y1880394D03*
Y1890394D03*
Y1900394D03*
Y1910394D03*
Y1920394D03*
X128937Y1778819D03*
X118937D03*
X165000Y1390500D03*
Y1380500D03*
Y1370500D03*
X138937Y1778819D03*
G54D32*
X30300Y1787800D03*
X64500Y573000D03*
X71200Y1144500D03*
X81900Y966200D03*
X87000Y1143000D03*
X94800Y1431500D03*
Y1434900D03*
Y1442800D03*
X163400Y549300D03*
X144300Y695500D03*
X133300Y1432000D03*
G54D41*
X77650Y103000D03*
X82250Y776700D03*
X75950Y1069700D03*
X68050D03*
X85550Y103000D03*
X90150Y776700D03*
G54D14*
X27559Y157480D03*
Y629921D03*
X17716Y1338583D03*
X27559Y1811023D03*
X179134Y78740D03*
X179133Y570866D03*
X179134Y1161417D03*
Y1889764D03*
G54D23*
X30000Y570800D03*
X24300Y1106000D03*
X18600Y1640200D03*
X19900Y1769600D03*
X67300Y63500D03*
X56900Y171300D03*
Y183300D03*
Y167300D03*
Y187300D03*
X57800Y221000D03*
X46500Y217400D03*
X32682Y264217D03*
X56900Y280000D03*
X78544Y694635D03*
X80000Y682200D03*
X65300Y730000D03*
X68700Y1004300D03*
X59600Y1020600D03*
X72300Y1025400D03*
X72400Y1020900D03*
X38000Y1096000D03*
X68800Y1175100D03*
X30700Y1774400D03*
X35000Y1788200D03*
X98700Y549600D03*
X83700Y569900D03*
X91300Y671000D03*
X115600Y660200D03*
X104900Y662200D03*
X87800Y707900D03*
X86300Y733400D03*
X104100Y1408100D03*
X129800Y1428300D03*
X91300Y1446500D03*
X109700Y1421600D03*
X150100Y430800D03*
X145300Y568000D03*
X152800Y587000D03*
X162700Y626700D03*
X174300Y624300D03*
X148004Y1394000D03*
X140500Y1466400D03*
Y1462400D03*
X140200Y1453300D03*
X157300Y1458000D03*
G54D50*
X73900Y550100D03*
X132735Y593429D03*
X125835Y593629D03*
X92971Y617335D03*
X131935Y601929D03*
X105000Y603200D03*
X101900Y654100D03*
X117100Y1430100D03*
X136771Y548521D03*
X144329Y598765D03*
X140135Y593229D03*
X160700Y615900D03*
X151029Y627565D03*
X139929Y604165D03*
X156700Y626800D03*
X179000Y706500D03*
X147600Y994600D03*
X154000Y994500D03*
X142000D03*
G54D51*
X35000Y581300D03*
X58100Y1030800D03*
X87400Y574100D03*
X149500Y578600D03*
X164600Y608500D03*
X150500Y699200D03*
G54D24*
X24100Y690900D03*
X28900D03*
X74100Y576200D03*
X65635Y693906D03*
X70535D03*
X82000Y708200D03*
X72200Y711000D03*
X67200D03*
X70800Y981400D03*
X64200Y1004100D03*
X81398Y1137753D03*
X92300Y878454D03*
X87500D03*
X94000Y962800D03*
X103500Y979800D03*
X129900Y992500D03*
X140400Y572400D03*
X158535Y609679D03*
G54D33*
X26700Y1787800D03*
X60900Y573000D03*
X78300Y966200D03*
X67600Y1144500D03*
X83400Y1143000D03*
X91200Y1431500D03*
Y1434900D03*
X129700Y1432000D03*
X91200Y1442800D03*
X159800Y549300D03*
X140700Y695500D03*
G54D60*
X57100Y974900D03*
G54D42*
X80709Y161889D03*
Y171889D03*
Y181889D03*
Y191889D03*
Y204409D03*
Y214409D03*
Y224409D03*
Y234409D03*
Y244409D03*
Y256929D03*
Y266929D03*
Y276929D03*
Y286929D03*
X110709Y161889D03*
Y171889D03*
X100709Y161889D03*
Y171889D03*
X90709Y161889D03*
Y171889D03*
X110709Y181889D03*
Y191889D03*
X100709Y181889D03*
Y191889D03*
X90709Y181889D03*
Y191889D03*
X110709Y204409D03*
Y214409D03*
Y224409D03*
Y234409D03*
Y244409D03*
X100709Y204409D03*
Y214409D03*
Y224409D03*
Y234409D03*
Y244409D03*
X90709Y204409D03*
Y214409D03*
Y224409D03*
Y234409D03*
Y244409D03*
X110709Y256929D03*
Y266929D03*
X100709Y256929D03*
Y266929D03*
X90709Y256929D03*
Y266929D03*
X110709Y276929D03*
Y286929D03*
X100709Y276929D03*
Y286929D03*
X90709Y276929D03*
Y286929D03*
X179606Y161889D03*
Y171889D03*
X169606Y161889D03*
Y171889D03*
X159606Y161889D03*
Y171889D03*
X149606Y161889D03*
Y171889D03*
X179606Y181889D03*
Y191889D03*
X169606Y181889D03*
Y191889D03*
X159606Y181889D03*
Y191889D03*
X149606Y181889D03*
Y191889D03*
X179606Y204409D03*
Y214409D03*
Y224409D03*
Y234409D03*
Y244409D03*
X169606Y204409D03*
Y214409D03*
Y224409D03*
Y234409D03*
Y244409D03*
X159606Y204409D03*
Y214409D03*
Y224409D03*
Y234409D03*
Y244409D03*
X149606Y204409D03*
Y214409D03*
Y224409D03*
Y234409D03*
Y244409D03*
X179606Y256929D03*
Y266929D03*
X169606Y256929D03*
Y266929D03*
X159606Y256929D03*
Y266929D03*
X149606Y256929D03*
Y266929D03*
X179606Y276929D03*
Y286929D03*
X169606Y276929D03*
Y286929D03*
X159606Y276929D03*
Y286929D03*
X149606Y276929D03*
Y286929D03*
G54D15*
X31299Y230866D03*
Y220866D03*
Y210866D03*
Y338563D03*
Y358563D03*
Y348563D03*
Y903917D03*
Y923917D03*
Y913917D03*
Y1054587D03*
Y1044587D03*
Y1064587D03*
Y1619941D03*
Y1609941D03*
Y1629941D03*
Y1757638D03*
Y1747638D03*
Y1737638D03*
G54D52*
X35000Y584900D03*
X58100Y1034400D03*
X87400Y577700D03*
X149500Y582200D03*
X164600Y612100D03*
X150500Y702800D03*
G54D16*
X27471Y262553D03*
X19721D03*
X23596Y255053D03*
X24925Y305350D03*
X28800Y312850D03*
X27625Y1649050D03*
X27292Y1714868D03*
X19542D03*
X23417Y1707368D03*
X32675Y305350D03*
X54817Y902368D03*
X58692Y909868D03*
X50942D03*
X78752Y1613297D03*
Y1619703D03*
X35375Y1649050D03*
X31500Y1641550D03*
X131525Y722550D03*
X109252Y1613297D03*
Y1619703D03*
X141625Y682250D03*
X149375D03*
X145500Y689750D03*
X139275Y722550D03*
X135400Y730050D03*
X148025Y1401454D03*
X155775D03*
X151900Y1408954D03*
X165494Y1437469D03*
X173244D03*
X169369Y1444969D03*
X138694Y1422269D03*
X146444D03*
X142569Y1429769D03*
X137752Y1613297D03*
Y1619703D03*
X165252Y1613297D03*
Y1619703D03*
G54D61*
X57100Y979300D03*
G54D70*
X89335Y544750D03*
X87370D03*
X85400D03*
X83430D03*
X81465D03*
Y561050D03*
X83430D03*
X85400D03*
X87370D03*
X89335D03*
X108710Y612629D03*
X110675D03*
X112645D03*
X114615D03*
X116580D03*
X118550D03*
X120520D03*
X122490D03*
X124455D03*
X126425D03*
X128395D03*
X130360D03*
Y646029D03*
X128395D03*
X126425D03*
X124455D03*
X122490D03*
X120520D03*
X118550D03*
X116580D03*
X114615D03*
X112645D03*
X110675D03*
X108710D03*
X153135Y542950D03*
X151170D03*
X149200D03*
X147230D03*
X145265D03*
Y559250D03*
X147230D03*
X149200D03*
X151170D03*
X153135D03*
G54D43*
X47498Y238899D03*
X52200Y238900D03*
X62700Y254200D03*
X45100Y577300D03*
X81500Y727600D03*
X63202Y1128347D03*
X103900Y476600D03*
X96300Y557700D03*
X129065Y673094D03*
X123465D03*
X124900Y722600D03*
X94500Y976700D03*
X130800Y975800D03*
X146700Y476700D03*
X163300Y696500D03*
X144300Y1111300D03*
X149002Y1111347D03*
X133500Y1471200D03*
G54D34*
X72200Y86200D03*
X72602Y757897D03*
X63700Y1050100D03*
X99000Y86200D03*
X99402Y757897D03*
X90500Y1050100D03*
G54D25*
X24100Y685300D03*
X28900D03*
X74100Y570600D03*
X82000Y702600D03*
X65635Y688306D03*
X70535D03*
X72200Y705400D03*
X67200D03*
X70800Y975800D03*
X64200Y998500D03*
X81398Y1132153D03*
X92300Y872854D03*
X87500D03*
X94000Y957200D03*
X103500Y974200D03*
X129900Y986900D03*
X140400Y566800D03*
X158535Y604079D03*
G54D35*
X78247Y61398D03*
X50600Y252800D03*
X34400Y294300D03*
X67900Y591000D03*
X71000Y986600D03*
X62000Y1025000D03*
X111300Y380100D03*
X85929Y533679D03*
X101500Y986000D03*
Y990800D03*
X89200Y1455500D03*
X101200Y1474500D03*
X160300Y532100D03*
X160100Y553300D03*
X176421Y613535D03*
X154700Y1462500D03*
G54D62*
X70202Y1138347D03*
Y1125047D03*
X41600Y1767550D03*
Y1754250D03*
X88502Y1136247D03*
Y1122947D03*
G54D17*
X27900Y246900D03*
X25300Y328500D03*
X16200Y1657100D03*
X27200D03*
X15800Y1699200D03*
X26800D03*
X38900Y246900D03*
X36300Y328500D03*
X124696Y1392300D03*
X106000Y1387500D03*
X117000D03*
X135696Y1392300D03*
X154000Y1387500D03*
X143000D03*
G54D71*
X102835Y640154D03*
Y638189D03*
Y636219D03*
Y634249D03*
Y632284D03*
Y630314D03*
Y628344D03*
Y626374D03*
Y624409D03*
Y622439D03*
Y620469D03*
Y618504D03*
X136235D03*
Y620469D03*
Y622439D03*
Y624409D03*
Y626374D03*
Y628344D03*
Y630314D03*
Y632284D03*
Y634249D03*
Y636219D03*
Y638189D03*
Y640154D03*
G54D44*
X47498Y244499D03*
X52200Y244500D03*
X62700Y259800D03*
X45100Y582900D03*
X81500Y733200D03*
X63202Y1133947D03*
X103900Y482200D03*
X96300Y563300D03*
X129065Y678694D03*
X123465D03*
X124900Y728200D03*
X94500Y982300D03*
X130800Y981400D03*
X146700Y482300D03*
X163300Y702100D03*
X144300Y1116900D03*
X149002Y1116947D03*
X133500Y1476800D03*
G54D26*
X27700Y1106000D03*
X22000Y1640200D03*
X23300Y1769600D03*
X70700Y63500D03*
X60300Y171300D03*
Y183300D03*
Y167300D03*
Y187300D03*
X61200Y221000D03*
X49900Y217400D03*
X36082Y264217D03*
X60300Y280000D03*
X33400Y570800D03*
X68700Y730000D03*
X72100Y1004300D03*
X63000Y1020600D03*
X75700Y1025400D03*
X75800Y1020900D03*
X41400Y1096000D03*
X72200Y1175100D03*
X34100Y1774400D03*
X38400Y1788200D03*
X102100Y549600D03*
X87100Y569900D03*
X81944Y694635D03*
X94700Y671000D03*
X119000Y660200D03*
X108300Y662200D03*
X83400Y682200D03*
X91200Y707900D03*
X89700Y733400D03*
X107500Y1408100D03*
X94700Y1446500D03*
X113100Y1421600D03*
X153500Y430800D03*
X148700Y568000D03*
X156200Y587000D03*
X166100Y626700D03*
X177700Y624300D03*
X151404Y1394000D03*
X133200Y1428300D03*
X143900Y1466400D03*
Y1462400D03*
X143600Y1453300D03*
X160700Y1458000D03*
G54D80*
X125000Y1409454D03*
X121125Y1401954D03*
X128875D03*
G54D53*
X73403Y633502D03*
Y606702D03*
X122097Y1125298D03*
Y1152098D03*
X98497Y1883198D03*
Y1909998D03*
G54D54*
X56000Y623450D03*
Y615550D03*
X80100Y1891950D03*
Y1899850D03*
X105100Y1135550D03*
Y1143450D03*
G54D72*
X89435Y642629D03*
Y635029D03*
X89500Y1461700D03*
Y1469300D03*
X172100Y549100D03*
Y541500D03*
X170100Y607600D03*
Y615200D03*
X152265Y608971D03*
Y601371D03*
X167000Y1457700D03*
Y1465300D03*
G54D63*
X80200Y1477500D03*
X107600Y558300D03*
X115200D03*
X87800Y1477500D03*
X106770Y1480640D03*
X99170D03*
X183700Y1606500D03*
X180700Y1641000D03*
X191300Y1606500D03*
X188300Y1641000D03*
G54D81*
X111882Y1461600D03*
X114441D03*
X117000D03*
X119559D03*
X122118D03*
Y1442400D03*
X119559D03*
X117000D03*
X114441D03*
X111882D03*
G54D27*
X24368Y1093083D03*
X31868Y1089208D03*
Y1096958D03*
X112018Y566991D03*
Y574741D03*
X104518Y570866D03*
X112018Y1255968D03*
Y1263718D03*
X104518Y1259843D03*
G54D90*
X142300Y1471800D03*
Y1480800D03*
G54D36*
X81300Y71500D03*
X63800Y662300D03*
Y657600D03*
X54300Y1764700D03*
X33600Y1769900D03*
X115800Y769100D03*
Y764100D03*
X105300Y1058400D03*
Y1053700D03*
X147447Y1878698D03*
X147400Y1883700D03*
X187900Y1652700D03*
Y1648000D03*
G54D18*
X26450Y274750D03*
X25500Y321200D03*
X21600Y333800D03*
X29500Y343500D03*
X23100Y342400D03*
X23400Y353500D03*
X29500Y410500D03*
X14000Y476000D03*
X28800Y533700D03*
X5304Y548800D03*
Y528900D03*
X5094Y574500D03*
X29500Y586500D03*
X23450Y577491D03*
X25148Y570800D03*
X27000Y573800D03*
X4594Y749000D03*
Y714000D03*
X5094Y1354500D03*
X26700Y1529800D03*
X28000Y1596800D03*
X13300Y1644300D03*
X10500Y1648800D03*
X13300Y1689600D03*
X19542Y1710518D03*
X29100Y1721550D03*
X19200Y1707000D03*
X25000Y1763800D03*
X26750Y1791100D03*
X27400Y1899400D03*
X70454Y60031D03*
X64500Y53000D03*
X64000Y67553D03*
X74000Y60500D03*
X79000Y65500D03*
X75000Y67500D03*
X81500Y75500D03*
X63500Y63500D03*
X59600Y125800D03*
X75300Y155300D03*
X49924Y153261D03*
X53000Y171500D03*
X65000Y166300D03*
X60350Y151950D03*
X39300Y181100D03*
X63500Y179300D03*
X53400Y191300D03*
X39300Y175500D03*
X43700Y181200D03*
X43400Y174325D03*
X32425Y177900D03*
X52700Y162300D03*
X64400Y183400D03*
X52500Y175200D03*
X70500Y190200D03*
X54400Y217000D03*
X65200Y207850D03*
X57424Y232974D03*
X42720Y233990D03*
X65000Y241500D03*
Y235400D03*
X54200Y220700D03*
Y207850D03*
X51700Y234800D03*
X41100Y231000D03*
X71400Y208150D03*
X69900Y236600D03*
X77900Y229034D03*
X70600Y217600D03*
X74800Y231800D03*
X69400Y226100D03*
X61300Y229400D03*
X38000Y228500D03*
X75300Y211300D03*
X72100Y221700D03*
X49700Y209700D03*
X53500Y199700D03*
X47800Y199200D03*
X64000Y199700D03*
X60300Y275700D03*
X57500Y268500D03*
X68000Y268000D03*
X70600Y250500D03*
X48500Y248600D03*
X42500Y254100D03*
X58936Y256289D03*
X36000Y260386D03*
X42500Y260200D03*
X34200Y284800D03*
X52500Y248500D03*
X32600Y290500D03*
X50800Y266400D03*
X54000Y275600D03*
X45800Y277800D03*
X43400Y272300D03*
X32675Y299500D03*
X78000Y429500D03*
X34000Y448000D03*
X33200Y468900D03*
X52100Y513100D03*
X46500Y511000D03*
X46000Y516000D03*
X51000Y529500D03*
X71445Y532192D03*
X72397Y528297D03*
X77800Y540300D03*
X33450Y574300D03*
X63400Y581400D03*
X49700Y568900D03*
X66000Y550500D03*
X65000Y561500D03*
X78400Y583700D03*
X70350Y558850D03*
X54600Y573400D03*
X75571Y692496D03*
X53000Y673500D03*
X57684Y697639D03*
X64000Y666600D03*
X66200Y653500D03*
X82000Y652000D03*
X52500Y682500D03*
X78494Y697835D03*
X53000Y695100D03*
X39800Y681400D03*
X43388Y694286D03*
X44500Y697500D03*
X60900Y670200D03*
X60500Y682540D03*
X76100Y686900D03*
X73000Y728000D03*
X69000Y726800D03*
X71500Y735500D03*
X73500Y732000D03*
X49500Y703500D03*
X46500Y705500D03*
X57500Y844500D03*
X72400Y822900D03*
X51200Y827000D03*
X61207Y828350D03*
X49600Y889400D03*
X55700Y880000D03*
X59500Y881600D03*
X57500Y890300D03*
X56000Y885500D03*
X64600Y882700D03*
X61600Y885200D03*
X67200Y888800D03*
X54300Y915500D03*
X54000Y996500D03*
X70800Y990500D03*
X57500Y987800D03*
Y984300D03*
X53800Y1006200D03*
X53500Y1025500D03*
X56000Y1021500D03*
X54500Y1035500D03*
X51000Y1018000D03*
X64500Y1099000D03*
X37500Y1099823D03*
X70500Y1161500D03*
X73163Y1158780D03*
X71100Y1171000D03*
X68800Y1178800D03*
X39400Y1381300D03*
X44500Y1380500D03*
X45500Y1400000D03*
X45000Y1428000D03*
X80000Y1472000D03*
X36400Y1523400D03*
X67700Y1568700D03*
X43500Y1620700D03*
X42700Y1606000D03*
X38400Y1596700D03*
X42500Y1673000D03*
X35500Y1670500D03*
X43600Y1668300D03*
X43300Y1646600D03*
X31400Y1648200D03*
X45500Y1690000D03*
X41500Y1692000D03*
X44500Y1678000D03*
X40300Y1703900D03*
X44100Y1685200D03*
X34000Y1691500D03*
X45300Y1776300D03*
X52500Y1756000D03*
X62000Y1877000D03*
X57900Y1899800D03*
X65300Y1886600D03*
X55900Y1881500D03*
X38700Y1893800D03*
X41500Y1889500D03*
X60300Y1892300D03*
X47000Y1886200D03*
X79900Y1923000D03*
X91500Y88500D03*
X97000Y51500D03*
X115500Y59500D03*
X98500Y73000D03*
X109000Y76500D03*
X115000D03*
X99500Y61000D03*
X89500Y49500D03*
X109500Y62000D03*
X84500Y56500D03*
X92500Y73000D03*
X88253Y65500D03*
X93500Y101500D03*
X93900Y111800D03*
X93000Y107000D03*
X91000Y97000D03*
X91500Y92500D03*
X104500Y101000D03*
X112000D03*
X117600Y234900D03*
X122100Y230100D03*
X85676Y231100D03*
X127200Y246000D03*
X122500Y441000D03*
X108100Y477650D03*
X91300Y528200D03*
X108900Y541300D03*
X102700Y541000D03*
X87700Y528000D03*
X132500Y539621D03*
X129000Y597000D03*
X124200Y568400D03*
X119800Y568300D03*
X88000Y586500D03*
X101000Y583000D03*
X96000Y588000D03*
X89000Y595000D03*
X87000Y591000D03*
X121000Y581500D03*
X124900Y582000D03*
X91300Y577000D03*
X92200Y553800D03*
X106300Y553200D03*
X116000Y596900D03*
X113655Y599363D03*
X110400Y550800D03*
X128900Y580500D03*
X122300Y575000D03*
X115300Y551800D03*
X131135Y639554D03*
X84200Y643865D03*
X87000Y648000D03*
X130000Y700500D03*
X122500D03*
X114500D03*
X105500Y702500D03*
X93000Y698500D03*
X88500Y700000D03*
X98000Y698500D03*
X86597Y681103D03*
X100200Y663900D03*
X122500Y653650D03*
X117400Y653100D03*
X118127Y663400D03*
X109005Y665890D03*
X114000Y663350D03*
X83850Y678109D03*
X91250Y704700D03*
X130000Y753000D03*
Y746000D03*
X119500Y746500D03*
Y739500D03*
X113500Y729000D03*
Y736000D03*
Y747000D03*
Y721000D03*
X106000Y709000D03*
X98000Y703000D03*
Y708000D03*
X86500Y723500D03*
X130000Y764000D03*
X119500Y757500D03*
X113500Y756000D03*
X118700Y840700D03*
X98900Y822900D03*
X114900Y824100D03*
X106404Y840700D03*
X100300Y841000D03*
X111500Y851600D03*
X101500Y874200D03*
X102300Y863438D03*
X107164Y862285D03*
X113400Y862200D03*
X125400Y983600D03*
Y992000D03*
X97300Y990800D03*
X83500Y976300D03*
Y972800D03*
X83000Y979800D03*
X94000Y971800D03*
X104000Y1049500D03*
X127200Y1015200D03*
X104000Y1062500D03*
X82094Y1112500D03*
X105000Y1181000D03*
X119500Y1261000D03*
X119000Y1255968D03*
X128700Y1408000D03*
X125000Y1398500D03*
X100860Y1402260D03*
X111000Y1394000D03*
X125100Y1402500D03*
X131174Y1412700D03*
X83200Y1455500D03*
X89000Y1428171D03*
X110000Y1429500D03*
X132000Y1436500D03*
X112750Y1491250D03*
X121000Y1506500D03*
X113000D03*
X117000D03*
X109000D03*
X133000Y1505500D03*
X128999Y1506499D03*
X125000Y1506500D03*
X132300Y1491100D03*
X108500Y1569000D03*
X83000Y1619703D03*
X113200Y1622800D03*
Y1619300D03*
X83050Y1616000D03*
X91100Y1922800D03*
X128900Y1923300D03*
X104600Y1923400D03*
X149500Y52000D03*
X135500Y441000D03*
X146960Y432400D03*
X142000Y478500D03*
X165300Y481100D03*
X144000Y509500D03*
X166100Y527900D03*
X147000Y529900D03*
X162500Y527900D03*
X159850Y541800D03*
X182588Y542288D03*
X159250Y590250D03*
X154600Y581500D03*
X133500Y575500D03*
X145800Y594400D03*
X137000Y589900D03*
X133500Y582000D03*
X134600Y586700D03*
X156300Y552100D03*
X142500Y550000D03*
X135000Y561500D03*
X142100Y581400D03*
X160000Y562500D03*
X147900Y588100D03*
X138900Y650100D03*
X174196Y628196D03*
X139200Y653900D03*
X150978Y687775D03*
X142648Y665429D03*
X165433Y692372D03*
X134600Y665600D03*
X161000Y674000D03*
X157500Y664500D03*
X149000Y677000D03*
X155200Y679500D03*
X161500Y691700D03*
X150700D03*
X166000Y751500D03*
X170000Y745500D03*
X161600Y739800D03*
X161500Y747500D03*
X146000Y726000D03*
X165900Y717300D03*
X147000Y703000D03*
X146000Y738000D03*
X175100Y710000D03*
X158600Y752600D03*
X153192Y705890D03*
X146000Y755000D03*
Y765500D03*
Y796500D03*
Y782500D03*
X166000Y760000D03*
X166500Y775500D03*
X161500Y759000D03*
Y768000D03*
Y778000D03*
X146500Y812000D03*
X146000Y824000D03*
X180000Y856000D03*
X162000Y817500D03*
X174000Y834500D03*
X168000Y830000D03*
X180000Y872500D03*
X179500Y884000D03*
X179900Y900900D03*
X157800Y898000D03*
X147500Y900500D03*
X179900Y925700D03*
X179800Y941400D03*
X180000Y912500D03*
X143000Y953032D03*
X146500Y953030D03*
X149772Y954121D03*
X152747Y952474D03*
X163200Y985200D03*
X163100Y978600D03*
X149800Y1008700D03*
X179000Y1005000D03*
X180000Y960400D03*
X180500Y973200D03*
X150500Y976500D03*
X155000Y974500D03*
X155500Y1030000D03*
X153500Y1033500D03*
X151500Y1030500D03*
X163000Y1042500D03*
X159500Y1062000D03*
X135601Y1416200D03*
X146500Y1397100D03*
X155900D03*
X139900Y1415100D03*
X134500Y1420000D03*
X169000Y1426750D03*
X158500Y1466500D03*
X151500Y1438500D03*
X157500Y1454800D03*
X142500Y1420500D03*
X142000Y1494800D03*
X147500Y1498000D03*
X153500Y1496500D03*
X135008Y1508245D03*
X143518Y1567520D03*
X177500Y1569500D03*
X141500Y1621600D03*
X141300Y1625000D03*
X169876Y1626303D03*
X173270Y1626517D03*
X170000Y1920500D03*
X162100Y1912000D03*
X151900Y1891400D03*
X146300Y1913700D03*
X142400Y1923800D03*
X176700Y1923900D03*
X177700Y1912800D03*
X152500Y1883100D03*
X157900Y1923100D03*
X133500Y1906500D03*
X201500Y165000D03*
X191400Y432405D03*
X202210Y638500D03*
X201500Y691500D03*
X202500Y666000D03*
X201500Y726500D03*
X202500Y755500D03*
X201500Y777000D03*
X201389Y797000D03*
X202500Y822000D03*
Y846500D03*
X202000Y859500D03*
Y890000D03*
X202210Y903500D03*
X202000Y875000D03*
X202500Y945500D03*
X202000Y918000D03*
X201500Y931500D03*
X202500Y1006000D03*
Y977500D03*
Y962000D03*
X201500Y991000D03*
X202000Y1037000D03*
Y1052000D03*
X201500Y1019000D03*
X201389Y1067000D03*
X201500Y1082500D03*
X195000Y1112000D03*
X201500Y1147000D03*
X202000Y1212000D03*
X202500Y1179000D03*
X202000Y1246000D03*
X201500Y1310000D03*
X202500Y1280000D03*
X201500Y1359500D03*
X200700Y1348500D03*
X201700Y1388300D03*
X201500Y1413000D03*
X202400Y1444000D03*
X201389Y1425500D03*
X202210Y1462000D03*
X201500Y1569000D03*
X202000Y1537500D03*
X202210Y1554000D03*
X187500Y1559500D03*
X196500Y1606500D03*
X191700Y1652700D03*
X192500Y1648000D03*
X192650Y1641500D03*
X200500Y1876500D03*
X184500Y1920500D03*
X201200Y1890500D03*
X201100Y1908800D03*
G54D45*
X56200Y252800D03*
X40000Y294300D03*
X73500Y591000D03*
X76600Y986600D03*
X67600Y1025000D03*
X83847Y61398D03*
X116900Y380100D03*
X91529Y533679D03*
X107100Y986000D03*
Y990800D03*
X94800Y1455500D03*
X106800Y1474500D03*
X165900Y532100D03*
X165700Y553300D03*
X182021Y613535D03*
X160300Y1462500D03*
G54D19*
X19283Y307282D03*
X25900Y1721700D03*
X57400Y207900D03*
X56900Y236600D03*
X56600Y191600D03*
X32700Y253500D03*
X63000Y264300D03*
X39200Y343800D03*
X81400Y530500D03*
X78400Y587600D03*
X49600Y573500D03*
X61400Y673400D03*
X57400D03*
X64100Y909400D03*
X77002Y1134497D03*
X32900Y1660800D03*
X96100Y530500D03*
X124900Y585204D03*
X120800D03*
X93065Y594071D03*
X97265D03*
X92465Y606971D03*
X95200Y662300D03*
X110900Y881400D03*
X102600D03*
X119300D03*
X122529Y952344D03*
X117529D03*
X112529D03*
X100500Y1420300D03*
X91500D03*
X83500Y1461800D03*
X105000Y1420300D03*
X107500Y1486800D03*
X170600Y529100D03*
X155600Y529000D03*
X158000Y575200D03*
X170200Y623700D03*
X180365Y642371D03*
X137765Y658671D03*
X154500Y683800D03*
X149500Y708300D03*
X147900Y999700D03*
X152100Y999800D03*
X163500Y994300D03*
X159500D03*
X143800Y999800D03*
X135000Y1408404D03*
X134700Y1400604D03*
X137500Y1440300D03*
G54D28*
X22000Y1644300D03*
X21800Y1720700D03*
X23600Y1692800D03*
X60300Y155300D03*
Y163300D03*
Y179300D03*
Y159300D03*
Y175300D03*
X49900Y213400D03*
X61200Y217000D03*
X60300Y199300D03*
X36200Y272300D03*
X32500Y321300D03*
X74200Y431300D03*
X64400Y577200D03*
X48800Y916400D03*
X72100Y999800D03*
X33500Y1083600D03*
X52800Y1769800D03*
X91703Y61502D03*
X89200Y71500D03*
X121300Y437500D03*
X81956Y690465D03*
X84100Y686400D03*
X129356Y692165D03*
X129256Y688065D03*
Y683665D03*
X116300Y670600D03*
X87396Y848500D03*
Y844100D03*
Y852900D03*
X87400Y865700D03*
Y857200D03*
Y861500D03*
X115300Y1408200D03*
X94700Y1451000D03*
X113100Y1425900D03*
X94700Y1439000D03*
X87700Y1484000D03*
X132200Y1482000D03*
X163300Y545600D03*
X166100Y622700D03*
X155729Y615065D03*
X175200Y701100D03*
X155496Y1415000D03*
X143900Y1458400D03*
X155500Y1423400D03*
X155496Y1419200D03*
X194200Y439500D03*
G54D64*
X78900Y1498700D03*
Y1523500D03*
X124298Y1908303D03*
Y1883503D03*
X145798Y1151303D03*
Y1126503D03*
G54D55*
X66875Y674606D03*
X69435D03*
X71995D03*
Y681106D03*
X66875D03*
G54D73*
X93206Y677415D03*
Y682415D03*
Y687415D03*
Y692415D03*
X113306D03*
Y687415D03*
Y682415D03*
Y677415D03*
G54D82*
X126600Y1457118D03*
Y1454559D03*
Y1452000D03*
Y1449441D03*
Y1446882D03*
X107400D03*
Y1449441D03*
Y1452000D03*
Y1454559D03*
Y1457118D03*
G54D91*
X161417Y1773425D03*
G54D37*
X67998Y56503D03*
X67398Y71003D03*
X61000Y240000D03*
X61600Y211300D03*
X60600Y195000D03*
X54300Y263300D03*
X58300D03*
X37200Y256900D03*
X62600Y249200D03*
X73700Y543300D03*
X78600Y574500D03*
X73900Y558800D03*
X39000Y581300D03*
X77200Y705900D03*
X77000Y730800D03*
X43400Y896100D03*
X81398Y1126103D03*
X63498Y1123803D03*
X63198Y1142003D03*
X48300Y1755700D03*
X116800Y588596D03*
X128900D03*
X91300Y573200D03*
X129335Y662029D03*
X104900Y662200D03*
X115600Y660200D03*
X116300Y670600D03*
X119600Y831800D03*
X111200D03*
X102900Y831796D03*
X121671Y939756D03*
X117300Y939700D03*
X110500D03*
X131500Y947800D03*
X123300Y1001300D03*
X119300D03*
X114800D03*
X99000Y979700D03*
X123000Y1424200D03*
X127500D03*
X95500Y1464200D03*
X118000Y1424200D03*
X95600Y1423700D03*
X129000Y1501700D03*
X125000D03*
X121000D03*
X117000D03*
X113000D03*
X109000D03*
X93500Y1479200D03*
X136779Y543071D03*
X145300Y582200D03*
X153500Y570000D03*
X136679Y557171D03*
X151335Y635829D03*
X148435Y653329D03*
X133535Y662029D03*
X144235Y653329D03*
X167700Y699600D03*
X154500Y702700D03*
X158500D03*
X149000Y949200D03*
X153000D03*
X157000D03*
X145000D03*
X140500Y947800D03*
X136000D03*
X139100Y1003100D03*
X135000Y1003200D03*
X156631Y1431081D03*
X160831Y1430281D03*
X152331Y1431081D03*
X165400Y1430200D03*
X151000Y1491200D03*
X146500D03*
X142000D03*
X137000Y1501700D03*
X133000D03*
X137900Y1491100D03*
X148500Y1474100D03*
G54D46*
X69635Y361900D03*
X110735Y361800D03*
X99365Y361900D03*
X140465Y361800D03*
X157835Y1507700D03*
X187565D03*
G54D92*
G01X-448201Y-82763D02*
Y-162763D01*
G01Y-118263D02*
X752899D01*
G01X-448201Y-162763D02*
X752899D01*
G01X-452201Y-66763D02*
G02I-12000J0D01*
G01X-457351D02*
G02I-6850J0D01*
G01X-464201Y-82763D02*
Y-50763D01*
G01X-448201Y-66763D02*
X-480201D01*
G01X-448201Y-82763D02*
X752899D01*
G01X-34601D02*
Y-162763D01*
G01X32750Y272300D02*
X28900D01*
X26450Y274750D01*
G01X32700Y256950D02*
X28050D01*
G01X19721Y262553D02*
Y267203D01*
G01X29050Y321300D02*
X25600D01*
X25500Y321200D01*
G01X21600Y333800D02*
Y332200D01*
X25300Y328500D01*
G01X35000Y584850D02*
X31150D01*
X29500Y586500D01*
G01X24100Y685100D02*
X28900D01*
G01D02*
X29300D01*
X36400Y678000D01*
X48500D01*
X53000Y673500D01*
G01X39300Y1105800D02*
X39100Y1106000D01*
X27750D01*
G01X31868Y1096958D02*
X27260D01*
X27218Y1097000D01*
G01X18550Y1644300D02*
X13300D01*
G01X16200Y1657100D02*
Y1650900D01*
X14100Y1648800D01*
X10500D01*
G01X18550Y1640200D02*
X7500D01*
G01X31400Y1648200D02*
X30550Y1649050D01*
X27625D01*
G01X13300Y1689600D02*
X16500Y1692800D01*
X20150D01*
G01X15800Y1699200D02*
Y1703900D01*
X13900Y1705800D01*
Y1706200D01*
G01X19542Y1714868D02*
Y1710518D01*
G01X25900Y1721650D02*
X29000D01*
X29100Y1721550D01*
G01X26750Y1787800D02*
Y1791100D01*
G01X70454Y60031D02*
Y63204D01*
X70750Y63500D01*
G01X67998Y53053D02*
X67945Y53000D01*
X64500D01*
G01X67398Y67553D02*
X64000D01*
G01X56850Y171300D02*
X53200D01*
X53000Y171500D01*
G01X60350Y155300D02*
Y151950D01*
G01Y179300D02*
X63500D01*
G01X60350Y163300D02*
X62000D01*
X65000Y166300D01*
G01X57750Y217000D02*
X54400D01*
G01X65200Y207850D02*
X61600D01*
G01X61000Y236550D02*
X62750D01*
X62800Y236500D01*
X63900D01*
X65000Y235400D01*
G01X62600Y245750D02*
Y243750D01*
X63600Y242750D01*
X63750D01*
X65000Y241500D01*
G01X61000Y236550D02*
X57424Y232974D01*
G01X42720Y233990D02*
X44910Y231800D01*
X56250D01*
X57424Y232974D01*
G01X70600Y250500D02*
Y247100D01*
X65000Y241500D01*
G01X57750Y221000D02*
X54500D01*
X54200Y220700D01*
G01Y207850D02*
X57400D01*
G01X60350Y280000D02*
X62900D01*
X65675Y277225D01*
Y272675D01*
X63000Y270000D01*
Y267750D01*
G01D02*
X67750D01*
X68000Y268000D01*
G01X47498Y244699D02*
Y247598D01*
X48500Y248600D01*
G01X52200Y244700D02*
X47499D01*
X47498Y244699D01*
G01X42500Y254100D02*
X38900Y250500D01*
Y246900D01*
G01X58936Y256289D02*
X61000Y254225D01*
Y254000D01*
X62700D01*
G01X37200Y256950D02*
Y259186D01*
X36000Y260386D01*
G01X35450Y343750D02*
X39200D01*
G01X32675Y305350D02*
Y299500D01*
G01X74250Y431300D02*
X76200D01*
X78000Y429500D01*
G01X84000Y440000D02*
Y437000D01*
X81800Y434800D01*
X73300D01*
X70750Y432250D01*
Y431300D01*
G01D02*
Y427350D01*
X70900Y427200D01*
G01X82000Y483600D02*
X74148Y491452D01*
G01D02*
X72000D01*
G01Y473548D02*
Y475500D01*
G01X78200Y481700D02*
X86352Y473548D01*
G01X72000Y475500D02*
X78200Y481700D01*
G01X81400Y533950D02*
X79750D01*
X77400Y536300D01*
G01X81400Y533950D02*
X85458D01*
X85729Y533679D01*
G01X81400Y530450D02*
X85250D01*
X87700Y528000D01*
G01X39000Y577850D02*
X37000D01*
X33450Y574300D01*
G01Y570800D02*
Y574300D01*
G01X58350Y593000D02*
Y584000D01*
G01D02*
X60800D01*
X63400Y581400D01*
G01X60950Y577200D02*
Y578450D01*
X63400Y580900D01*
Y581400D01*
G01X78400Y587550D02*
Y583700D01*
G01X73900Y558850D02*
X70350D01*
G01X78600Y574550D02*
Y577900D01*
X79458Y578758D01*
G01X74100Y576400D02*
X72000D01*
X69800Y574200D01*
G01X49600Y573450D02*
X54550D01*
X54600Y573400D01*
G01X60950Y573000D02*
X55000D01*
X54600Y573400D01*
G01X67200Y705200D02*
X67300Y705100D01*
Y702200D01*
X62739Y697639D01*
X57684D01*
G01X78506Y690465D02*
Y689593D01*
X80650Y687449D01*
Y686400D01*
G01X65635Y688106D02*
X70535D01*
G01X57400Y676850D02*
X61400D01*
G01X78506Y690465D02*
X77617Y689576D01*
X75475D01*
X75399Y689500D01*
X71929D01*
X70535Y688106D01*
G01X57400Y676850D02*
Y680379D01*
X56710Y681069D01*
G01X65635Y688106D02*
X63100Y685571D01*
Y680200D01*
X61400Y678500D01*
Y676850D01*
G01X80650Y686400D02*
X79050Y684800D01*
X78278D01*
X78078Y684600D01*
X77600D01*
X76000Y683000D01*
Y679700D01*
X88000Y667700D01*
X93250D01*
X95200Y665750D01*
G01X70535Y694106D02*
Y695065D01*
X69100Y696500D01*
Y698006D01*
G01X64000Y662300D02*
Y666600D01*
G01Y657600D02*
Y655700D01*
X66200Y653500D01*
G01X78494Y694635D02*
Y697835D01*
G01X72200Y705200D02*
X67200D01*
G01X69000Y726800D02*
Y727000D01*
X68750Y727250D01*
Y730000D01*
G01X71500Y735500D02*
X72500D01*
X74950Y737950D01*
X75200D01*
G01X77000Y730850D02*
X74650D01*
X73500Y732000D01*
G01X57500Y844500D02*
X57900Y844100D01*
X83946D01*
G01X43400Y892650D02*
X46650Y889400D01*
X49600D01*
G01X49900Y883800D02*
X51900D01*
X55700Y880000D01*
G01X54300Y915500D02*
Y913400D01*
X50942Y910042D01*
Y909868D01*
G01X48850Y916400D02*
X53400D01*
X54300Y915500D01*
G01X64000Y980500D02*
X63950Y980450D01*
X57100D01*
G01X72150Y1004300D02*
Y1010500D01*
X73450Y1011800D01*
G01X63800Y986600D02*
X62600D01*
X60300Y984300D01*
X57500D01*
G01X53800Y1009550D02*
Y1006200D01*
G01X70800Y975600D02*
X63800D01*
G01X70800D02*
X71500Y976300D01*
X77400D01*
G01X31600Y1024300D02*
X33400Y1022500D01*
X39000D01*
G01X75850Y1020900D02*
Y1014200D01*
X73450Y1011800D01*
G01X75750Y1025400D02*
Y1021000D01*
X75850Y1020900D01*
G01X75750Y1025400D02*
Y1030100D01*
X77750Y1032100D01*
G01X59550Y1020600D02*
X56900D01*
X56000Y1021500D01*
G01X58100Y1034350D02*
X55650D01*
X54500Y1035500D01*
G01X33550Y1083600D02*
Y1080100D01*
G01X63700Y1090600D02*
Y1098200D01*
X64500Y1099000D01*
G01X66000Y1149500D02*
X63198Y1146698D01*
Y1142053D01*
G01X67650Y1144500D02*
Y1147850D01*
X66000Y1149500D01*
G01X83450Y1143000D02*
X80156D01*
X79044Y1144112D01*
G01X77002Y1134447D02*
X76447D01*
X74000Y1132000D01*
G01X72250Y1175100D02*
Y1172150D01*
X71100Y1171000D01*
G01X80000Y1472000D02*
X80200Y1472200D01*
Y1477500D01*
G01X67700Y1568700D02*
X72200D01*
X75400Y1571900D01*
Y1575600D01*
G01X34000Y1691500D02*
X32359Y1689859D01*
Y1680500D01*
G01X34150Y1774400D02*
X38200D01*
X38800Y1775000D01*
G01X41600Y1754250D02*
Y1746900D01*
G01X48400D02*
Y1752150D01*
X48300Y1752250D01*
G01X34650Y1781000D02*
X37650Y1784000D01*
X41600D01*
X42000Y1784400D01*
G01D02*
X38450Y1787950D01*
Y1788200D01*
G01X102899Y-82763D02*
Y-162763D01*
G01X122500Y441000D02*
X121350Y439850D01*
Y437500D01*
G01X111500Y439500D02*
X113500Y437500D01*
X117850D01*
G01X118500Y442000D02*
X117850Y441350D01*
Y437500D01*
G01X82000Y483600D02*
X89852Y491452D01*
G01D02*
X90000D01*
G01X108100Y477650D02*
X105150D01*
X103900Y476400D01*
G01X86352Y473548D02*
X90000D01*
G01X96100Y530450D02*
X93550D01*
X91300Y528200D01*
G01X86850Y537800D02*
Y534800D01*
X85729Y533679D01*
G01X90350Y537800D02*
Y535058D01*
X91729Y533679D01*
G01X96100Y533950D02*
X92000D01*
X91729Y533679D01*
G01X96150Y537800D02*
Y534000D01*
X96100Y533950D01*
G01X96900Y541600D02*
X96150Y540850D01*
Y537800D01*
G01X86900Y549900D02*
X91400D01*
X95700Y545600D01*
X99800D01*
G01D02*
X100100D01*
X102150Y547650D01*
Y549600D01*
G01X136779Y539621D02*
X132500D01*
G01X158535Y603879D02*
Y596035D01*
X154300Y591800D01*
X146600D01*
X136600Y581800D01*
Y574198D01*
X126393Y563991D01*
X105521D01*
X97500Y572012D01*
Y581700D01*
X93065Y586135D01*
Y594021D01*
G01X103500Y593950D02*
Y588000D01*
X103100Y587600D01*
G01X87400Y577650D02*
Y581005D01*
X87595Y581200D01*
Y581300D01*
G01X124900Y585154D02*
Y582000D01*
G01X120800Y585154D02*
Y581700D01*
X121000Y581500D01*
G01X91300Y573250D02*
Y577000D01*
G01X96300Y557500D02*
X95900D01*
X92200Y553800D01*
G01X102150Y553300D02*
X106200D01*
X106300Y553200D01*
G01X102150Y549600D02*
X109200D01*
X110400Y550800D01*
G01X98650Y553300D02*
Y549600D01*
G01X101800Y557400D02*
X101700D01*
X98650Y554350D01*
Y553300D01*
G01X128900Y585146D02*
Y580500D01*
G01X122300Y575000D02*
X119897D01*
X116800Y578097D01*
Y585146D01*
G01X89435Y642629D02*
X85436D01*
X84200Y643865D01*
G01X129065Y678894D02*
X123465D01*
G01D02*
X121986Y677415D01*
X113306D01*
G01D02*
Y675706D01*
X108700Y671100D01*
X106700D01*
X103300Y667700D01*
X97150D01*
X95200Y665750D01*
G01X129065Y678894D02*
X136454D01*
X145548Y669800D01*
G01X123465Y672894D02*
X119406D01*
X119000Y673300D01*
G01X129065Y672894D02*
X132494D01*
X134100Y674500D01*
G01X103256Y684915D02*
Y690611D01*
X99001Y694866D01*
G01X129306Y683665D02*
Y688065D01*
G01D02*
Y691565D01*
X129406Y691665D01*
Y692165D01*
G01X129800Y696800D02*
X129406Y696406D01*
G01D02*
Y692165D01*
G01X91250Y707900D02*
Y704700D01*
G01X117291Y710500D02*
Y706791D01*
X115000Y704500D01*
G01X124900Y728400D02*
X133750D01*
X135400Y730050D01*
G01X116000Y764100D02*
X117200D01*
X121000Y767900D01*
G01X116000Y769100D02*
X119800D01*
X121000Y767900D01*
G01X83946Y844100D02*
Y848500D01*
G01D02*
Y852900D01*
G01X83950Y857200D02*
Y852904D01*
X83946Y852900D01*
G01X83950Y865700D02*
Y861500D01*
G01X92300Y872654D02*
X87500D01*
G01X83950Y865700D02*
Y869104D01*
X87500Y872654D01*
G01X83950Y861500D02*
Y857200D01*
G01X121671Y936306D02*
X127500D01*
X131306Y932500D01*
X141300D01*
X145000Y936200D01*
Y945750D01*
G01X112529Y952294D02*
Y952029D01*
X110000Y949500D01*
G01X117529Y952294D02*
Y948844D01*
G01X93000Y925500D02*
X96000Y928500D01*
Y931000D01*
G01X168000Y977500D02*
X162002Y971502D01*
X128998D01*
X126500Y974000D01*
Y977546D01*
X125046Y979000D01*
G01X107300Y990800D02*
X112000D01*
G01X107300Y986000D02*
Y990800D01*
G01X130800Y981600D02*
X128200Y979000D01*
X125046D01*
G01D02*
X124710Y979336D01*
X112364D01*
X107300Y984400D01*
Y986000D01*
G01X101300Y990800D02*
X97300D01*
G01X101300Y986000D02*
Y990800D01*
G01X94500Y976500D02*
X88200D01*
X88000Y976300D01*
G01D02*
X83500D01*
G01X114800Y1001350D02*
Y1005000D01*
G01X104000Y1062500D02*
X105500Y1061000D01*
Y1058400D01*
G01X104000Y1049500D02*
X105500Y1051000D01*
Y1053700D01*
G01X110000Y1418000D02*
X109650Y1418350D01*
Y1421600D01*
G01X128875Y1401954D02*
X125646D01*
X125100Y1402500D01*
G01X125000Y1398500D02*
X125500Y1398000D01*
X132146D01*
X134700Y1400554D01*
G01X124696Y1392300D02*
Y1398196D01*
X125000Y1398500D01*
G01X129750Y1432000D02*
Y1428300D01*
G01X132200Y1424800D02*
Y1424978D01*
X129750Y1427428D01*
Y1428300D01*
G01X91250Y1446500D02*
X87700D01*
G01X95500Y1468000D02*
Y1464250D01*
G01X89500Y1469300D02*
X94200D01*
X95500Y1468000D01*
G01X94000Y1427800D02*
X95600Y1426200D01*
Y1423750D01*
G01X87200Y1431900D02*
X87600Y1431500D01*
X91250D01*
G01X136100Y1463900D02*
Y1461300D01*
X131900Y1457100D01*
G01X83500Y1465250D02*
Y1469500D01*
G01X91250Y1439000D02*
X88200D01*
X87200Y1440000D01*
G01X95000Y1455500D02*
X97400D01*
X97500Y1455600D01*
X99800D01*
G01X94750Y1451000D02*
X95000Y1451250D01*
Y1455500D01*
G01X89000Y1428171D02*
Y1426250D01*
X91500Y1423750D01*
G01X94750Y1439000D02*
Y1442800D01*
G01Y1446500D02*
X95100D01*
X96537Y1447937D01*
X96637D01*
X99400Y1450700D01*
X99700D01*
G01X94750Y1442800D02*
Y1446500D01*
G01X129000Y1473750D02*
Y1470500D01*
X127300Y1468800D01*
G01D02*
X124400Y1465900D01*
G01X93500Y1479250D02*
Y1482700D01*
G01X99170Y1480640D02*
Y1485790D01*
G01X101000Y1474500D02*
Y1473000D01*
X103700Y1470300D01*
G01X85000Y1490000D02*
X84250Y1489250D01*
Y1484000D01*
G01X107500Y1490250D02*
X105949Y1491801D01*
X86801D01*
X85000Y1490000D01*
G01X112750Y1491250D02*
X108500D01*
X107500Y1490250D01*
G01X129000Y1477250D02*
Y1481750D01*
X128750Y1482000D01*
G01X130180Y1486680D02*
X128750Y1485250D01*
Y1482000D01*
G01X137800Y1487750D02*
X131250D01*
X130180Y1486680D01*
G01X132250Y1482000D02*
X135925D01*
X136500Y1481425D01*
G01X132300Y1491100D02*
X137850D01*
X137900Y1491150D01*
G01X108500Y1575500D02*
Y1569000D01*
G01X156000Y439500D02*
Y433250D01*
X153550Y430800D01*
G01X156000Y439500D02*
X161281D01*
X162612Y438169D01*
G01X150050Y430800D02*
X148560D01*
X146960Y432400D01*
G01X158000Y490952D02*
X160448D01*
Y490852D01*
G01X169200Y482800D02*
X176000Y489600D01*
G01X160448Y490852D02*
X168500Y482800D01*
X169200D01*
G01X176000Y489600D02*
Y490952D01*
G01X146700Y476500D02*
X144000D01*
X142000Y478500D01*
G01X165300Y481100D02*
X158000Y473800D01*
G01X165300Y481100D02*
Y481000D01*
X173252Y473048D01*
G01X158000Y473800D02*
Y473048D01*
G01X173252D02*
X176000D01*
G01X166100Y527900D02*
X169450D01*
X170600Y529050D01*
G01X164450Y536500D02*
Y533750D01*
X166100Y532100D01*
G01X170600Y532550D02*
X166550D01*
X166100Y532100D01*
G01X170650Y536400D02*
Y532600D01*
G01D02*
X174400D01*
X174800Y532200D01*
G01X170650Y532600D02*
X170600Y532550D01*
G01X160950Y536500D02*
Y532950D01*
X160100Y532100D01*
G01X155600Y532450D02*
X159750D01*
X160100Y532100D01*
G01X155600Y532450D02*
X152050D01*
X151500Y533000D01*
G01X163350Y545600D02*
Y549300D01*
G01X164200Y541900D02*
Y544750D01*
X163350Y545600D01*
G01X162500Y527900D02*
X156650D01*
X155600Y528950D01*
G01X159850Y541800D02*
Y545600D01*
G01D02*
X157800D01*
X155392Y548008D01*
X151072D01*
G01X159250Y590250D02*
Y590000D01*
X156250Y587000D01*
G01X158000Y578650D02*
X157450D01*
X154600Y581500D01*
G01X140400Y572400D02*
Y572600D01*
G01X150500Y596000D02*
X152265Y597765D01*
Y601371D01*
G01X153500Y570050D02*
Y574359D01*
G01X142100Y581400D02*
X142950Y582250D01*
X145300D01*
G01X140400Y572600D02*
Y576300D01*
X140700Y576600D01*
G01X159850Y549300D02*
Y553250D01*
X159900Y553300D01*
G01D02*
X157500D01*
X156300Y552100D01*
G01X180465Y634971D02*
X171522D01*
X171370Y634819D01*
G01X182221Y613535D02*
Y610118D01*
X173903Y601800D01*
X160614D01*
X158535Y603879D01*
G01X180465Y634971D02*
X182029D01*
X183700Y633300D01*
Y615014D01*
X182221Y613535D01*
G01X180465Y634971D02*
Y642221D01*
X180365Y642321D01*
G01D02*
X181621D01*
X183194Y643894D01*
Y649006D01*
X162400Y669800D01*
X145548D01*
G01X165600Y630269D02*
X164765D01*
X162750Y628254D01*
Y626800D01*
X162650Y626700D01*
G01X164600Y612050D02*
Y615350D01*
X164950Y615700D01*
G01X180465Y631371D02*
Y628535D01*
X180500Y628500D01*
Y627771D01*
G01X175800Y617635D02*
X172535D01*
X170100Y615200D01*
G01X146365Y607771D02*
Y604865D01*
X145500Y604000D01*
G01X159700Y652000D02*
X159800Y651900D01*
Y645839D01*
G01X177750Y624300D02*
Y625238D01*
X174792Y628196D01*
X174196D01*
G01X145548Y669800D02*
Y664227D01*
X145409Y664088D01*
Y663907D01*
X143623Y662121D01*
X137765D01*
G01X134600Y665600D02*
X133535Y664535D01*
Y662079D01*
G01X149375Y682250D02*
Y677375D01*
X149000Y677000D01*
G01X165433Y692372D02*
X163300Y694505D01*
Y696300D01*
G01X150500Y702750D02*
X147250D01*
X147000Y703000D01*
G01Y732000D02*
Y737000D01*
X146000Y738000D01*
G01X158600Y752600D02*
X151822D01*
X135400Y736178D01*
Y730050D01*
G01X157000Y945750D02*
X162750D01*
X168000Y951000D01*
Y977500D01*
G01X149000Y945750D02*
X145000D01*
G01X157000D02*
X153000D01*
G01X149000D02*
X153000D01*
G01X168000Y977500D02*
Y995000D01*
X165250Y997750D01*
X163500D01*
G01D02*
X159500D01*
G01X152100Y1003250D02*
X154000D01*
X159500Y997750D01*
G01X147900Y1003150D02*
X152000D01*
X152100Y1003250D01*
G01X143800D02*
X147800D01*
X147900Y1003150D01*
G01X154600Y1111000D02*
X154453Y1111147D01*
X149002D01*
G01X146500Y1417619D02*
Y1422213D01*
X146444Y1422269D01*
G01X146500Y1397100D02*
Y1396954D01*
X147954Y1395500D01*
Y1394000D01*
G01X155775Y1401454D02*
Y1397225D01*
X155900Y1397100D01*
G01X154000Y1387500D02*
X153000D01*
X148000Y1392500D01*
Y1393954D01*
X147954Y1394000D01*
G01X139900Y1415100D02*
X140900Y1414100D01*
X151146D01*
X152046Y1415000D01*
G01Y1419200D02*
Y1415000D01*
G01X143950Y1458400D02*
X147900D01*
X149507Y1460007D01*
X149686D01*
G01X154500Y1462500D02*
X151500Y1459500D01*
X150193D01*
X149686Y1460007D01*
G01X133500Y1471000D02*
Y1467100D01*
G01X173244Y1437469D02*
X173375Y1437338D01*
Y1432500D01*
G01X165400Y1426750D02*
X169000D01*
G01X140450Y1466400D02*
X138600D01*
X136100Y1463900D01*
G01X167000Y1465300D02*
X165800Y1466500D01*
X158500D01*
G01X152050Y1423400D02*
Y1427350D01*
X152331Y1427631D01*
G01X152046Y1419200D02*
Y1423396D01*
X152050Y1423400D01*
G01X152500Y1456000D02*
X151000Y1454500D01*
X148000D01*
X146800Y1453300D01*
X143650D01*
G01X142000Y1491250D02*
Y1494800D01*
G01X146500Y1491250D02*
Y1497000D01*
X147500Y1498000D01*
G01X151000Y1491250D02*
Y1494000D01*
X153500Y1496500D01*
G01X137800Y1487750D02*
X137900Y1487650D01*
G01X142300Y1480800D02*
Y1487450D01*
X142000Y1487750D01*
G01X146500D02*
X142000D01*
G01X151000D02*
X146500D01*
G01X142000D02*
X137800D01*
G01X136500Y1481425D02*
Y1480000D01*
X133500Y1477000D01*
G01X148500Y1474150D02*
X144650D01*
X142300Y1471800D01*
G01X148500Y1479500D02*
Y1474150D01*
G01X143500Y1575500D02*
Y1567538D01*
X143518Y1567520D01*
G01X177500Y1575500D02*
Y1569500D01*
G01X217899Y-82763D02*
Y-162763D01*
G01X191400Y432405D02*
Y432500D01*
X194250Y435350D01*
Y439500D01*
G01X184000D02*
X190750D01*
G01X189928Y435800D02*
X190750Y436622D01*
Y439500D01*
G01X385399Y-82763D02*
Y-162763D01*
G01X555399Y-82763D02*
Y-162763D01*
G01X752899Y-82763D02*
Y-162763D01*
G01X780899Y-66763D02*
G02I-12000J0D01*
G01X775749D02*
G02I-6850J0D01*
G01X768899Y-82763D02*
Y-50763D01*
G01X784899Y-66763D02*
X752899D01*
G54D83*
X117000Y1452000D03*
G54D56*
X51750Y690560D03*
Y688000D03*
Y685440D03*
X58250D03*
Y690560D03*
X36250D03*
Y688000D03*
Y685440D03*
X42750D03*
Y690560D03*
G54D65*
X71250Y1613297D03*
Y1619703D03*
X101750Y1613297D03*
Y1619703D03*
X130250Y1613297D03*
Y1619703D03*
X157750Y1613297D03*
Y1619703D03*
G54D47*
X69000Y440000D03*
X74000D03*
X79000D03*
X60400Y1575600D03*
X65400D03*
X70400D03*
X75400D03*
X96500Y439500D03*
X101500D03*
X106500D03*
X111500D03*
X84000Y440000D03*
X128500Y1575500D03*
X93500D03*
X98500D03*
X103500D03*
X108500D03*
X141000Y439500D03*
X146000D03*
X151000D03*
X156000D03*
X169000D03*
X174000D03*
X179000D03*
X184000D03*
X162500Y1575500D03*
X167500D03*
X172500D03*
X177500D03*
X133500D03*
X138500D03*
X143500D03*
G54D74*
X103256Y684915D03*
G54D38*
X67998Y53103D03*
X67398Y67603D03*
X61000Y236600D03*
X61600Y207900D03*
X60600Y191600D03*
X54300Y259900D03*
X58300D03*
X37200Y253500D03*
X62600Y245800D03*
X73700Y539900D03*
X78600Y571100D03*
X73900Y555400D03*
X39000Y577900D03*
X77200Y702500D03*
X77000Y727400D03*
X43400Y892700D03*
X81398Y1122703D03*
X63498Y1120403D03*
X63198Y1138603D03*
X48300Y1752300D03*
X116800Y585196D03*
X128900D03*
X91300Y569800D03*
X129335Y658629D03*
X104900Y658800D03*
X115600Y656800D03*
X116300Y667200D03*
X119600Y828400D03*
X111200D03*
X102900Y828396D03*
X121671Y936356D03*
X117300Y936300D03*
X110500D03*
X131500Y944400D03*
X123300Y997900D03*
X119300D03*
X114800D03*
X99000Y976300D03*
X123000Y1420800D03*
X127500D03*
X95500Y1460800D03*
X118000Y1420800D03*
X95600Y1420300D03*
X129000Y1498300D03*
X125000D03*
X121000D03*
X117000D03*
X113000D03*
X109000D03*
X93500Y1475800D03*
X136779Y539671D03*
X145300Y578800D03*
X153500Y566600D03*
X136679Y553771D03*
X151335Y632429D03*
X148435Y649929D03*
X144235D03*
X133535Y658629D03*
X154500Y699300D03*
X167700Y696200D03*
X158500Y699300D03*
X149000Y945800D03*
X153000D03*
X157000D03*
X145000D03*
X140500Y944400D03*
X136000D03*
X139100Y999700D03*
X135000Y999800D03*
X156631Y1427681D03*
X160831Y1426881D03*
X152331Y1427681D03*
X165400Y1426800D03*
X151000Y1487800D03*
X146500D03*
X142000D03*
X137000Y1498300D03*
X133000D03*
X137900Y1487700D03*
X148500Y1470700D03*
G54D29*
X32359Y1680500D03*
X60641D03*
G54D93*
G01X73700Y539850D02*
X74150Y540300D01*
X77800D01*
G01X83430Y544750D02*
Y541080D01*
X82650Y540300D01*
X77800D01*
G01X81465Y561050D02*
Y563935D01*
X79700Y565700D01*
X79122D01*
G01X66875Y681106D02*
Y686866D01*
X65635Y688106D01*
G01X85400Y544750D02*
Y548400D01*
X86900Y549900D01*
G01X130800Y981600D02*
X137240D01*
X137340Y981700D01*
G01X153135Y542950D02*
Y539665D01*
X153900Y538900D01*
X163100D01*
X164450Y537550D01*
Y536500D01*
G01X160950D02*
X152600D01*
X151170Y537930D01*
Y542950D01*
G01X136779Y539621D02*
X138600Y537800D01*
X146030D01*
X147230Y539000D01*
Y542950D01*
G01X151072Y548008D02*
X149200Y546136D01*
Y542950D01*
G01X171175Y710104D02*
X174996D01*
X175100Y710000D01*
G54D66*
X96457Y1773425D03*
G54D48*
X76500Y454565D03*
X67900Y1590165D03*
X104000Y454065D03*
X136000Y1590065D03*
X101000D03*
X148500Y454065D03*
X176500D03*
X170000Y1590065D03*
G54D57*
X49900Y883800D03*
Y894800D03*
X63800Y986600D03*
Y975600D03*
X39000Y1022500D03*
Y1033500D03*
X96000Y931000D03*
Y942000D03*
X147000Y732000D03*
Y721000D03*
G54D75*
X134709Y710500D03*
X117291D03*
G54D39*
X71802Y56547D03*
X71400Y71754D03*
X75200Y741500D03*
X75700Y719100D03*
X53800Y1013100D03*
X103500Y597500D03*
X146365Y611321D03*
G54D84*
X129000Y1476850D03*
G54D94*
G01X104500Y932700D02*
Y924000D01*
X101800Y921300D01*
X87700D01*
X80400Y928600D01*
Y928616D01*
X78116Y930900D01*
X78100D01*
X77101Y931899D01*
X41000D01*
G01X51500Y974100D02*
X56750D01*
G01D02*
X57100Y974450D01*
G01X64500Y1165700D02*
X87300D01*
X89000Y1167400D01*
G54D58*
X63901Y949600D03*
X86699D03*
G54D76*
X116175Y846304D03*
X113620D03*
X111060D03*
X108500D03*
X105940D03*
X103380D03*
X100825D03*
Y868504D03*
X103380D03*
X105940D03*
X108500D03*
X111060D03*
X113620D03*
X116175D03*
X113960Y985200D03*
X116520D03*
X119080D03*
X121640D03*
Y963000D03*
X119080D03*
X116520D03*
X113960D03*
X155825Y732304D03*
X158380D03*
X160940D03*
X163500D03*
X166060D03*
X168620D03*
X171175D03*
Y710104D03*
X168620D03*
X166060D03*
X163500D03*
X160940D03*
X158380D03*
X155825D03*
X137340Y959500D03*
X139900D03*
X142460D03*
X145020D03*
X147580D03*
X150140D03*
X152700D03*
X155260D03*
Y981700D03*
X152700D03*
X150140D03*
X147580D03*
X145020D03*
X142460D03*
X139900D03*
X137340D03*
G54D49*
X72000Y473548D03*
Y491452D03*
X90000Y473548D03*
Y491452D03*
X176000Y473048D03*
Y490952D03*
X158000Y473048D03*
Y490952D03*
G54D67*
X48200Y1760300D03*
X86800Y537800D03*
X96100D03*
X98600Y553300D03*
X107600Y593700D03*
X112900Y603500D03*
X170600Y536400D03*
X160900Y536500D03*
G54D85*
X129000Y1474150D03*
G54D95*
G01X92300Y872654D02*
X96450Y868504D01*
X100825D01*
G01X112000Y990800D02*
X113960Y988840D01*
Y985200D01*
G54D77*
X104500Y933512D03*
G54D86*
X171370Y634819D03*
X159800D03*
X171370Y645839D03*
X159800D03*
G54D59*
X77400Y980050D03*
Y976300D03*
Y972550D03*
X88000D03*
Y976300D03*
Y980050D03*
G54D68*
X51800Y1760300D03*
X90400Y537800D03*
X99700D03*
X102200Y553300D03*
X111200Y593700D03*
X116500Y603500D03*
X174200Y536400D03*
X164500Y536500D03*
G54D96*
G01X131900Y1457100D02*
Y1456100D01*
X130359Y1454559D01*
X126600D01*
G01X99800Y1455600D02*
X100841Y1454559D01*
X107400D01*
G01X126600Y1452000D02*
X132200D01*
X134400Y1454200D01*
Y1454300D01*
G01X99700Y1450700D02*
X101000Y1452000D01*
X107400D01*
G01X124400Y1465900D02*
X122118Y1463618D01*
Y1461600D01*
G01X140450Y1458400D02*
X138100D01*
X134400Y1454700D01*
Y1454300D01*
G01X140450Y1462400D02*
Y1458400D01*
G54D69*
X96457Y1747835D03*
Y1823031D03*
X178937Y1328740D03*
X161417Y1747835D03*
Y1823031D03*
G54D78*
X104500Y939475D03*
G54D87*
X180465Y631371D03*
Y634971D03*
G54D97*
G01X57684Y697639D02*
X55323Y700000D01*
X43000D01*
X39131Y696131D01*
Y693869D01*
X42440Y690560D01*
X42750D01*
G01X58250D02*
Y697073D01*
X57684Y697639D01*
G01X106400Y1402260D02*
X100860D01*
G01X113800Y1397140D02*
Y1396800D01*
X111000Y1394000D01*
G01X126600Y1457118D02*
Y1461500D01*
G54D88*
X141100Y1401696D03*
Y1410096D03*
X158600Y1446404D03*
Y1438004D03*
G54D79*
X113800Y1397140D03*
Y1399700D03*
Y1402260D03*
X106400D03*
Y1399700D03*
Y1397140D03*
G54D98*
G01X15906Y73908D02*
Y78110D01*
G01D02*
Y82312D01*
G01X11704Y78110D02*
X15906D01*
G01D02*
X20108D01*
G01X15906Y88110D02*
Y92312D01*
G01X11704Y88110D02*
X15906D01*
G01D02*
X20108D01*
G01X27559Y140328D02*
Y157480D01*
G01D02*
Y174632D01*
G01X10407Y157480D02*
X27559D01*
G01D02*
X44711D01*
G01X15906Y511339D02*
Y515541D01*
G01X11704Y511339D02*
X15906D01*
G01D02*
X20108D01*
G01X27559Y612769D02*
Y629921D01*
G01D02*
Y647073D01*
G01X10407Y629921D02*
X27559D01*
G01X15906Y766979D02*
Y771181D01*
G01D02*
Y775383D01*
G01X11704Y771181D02*
X15906D01*
G01D02*
X20108D01*
G01X15906Y781181D02*
X20108D01*
G01X15906D02*
X19077Y784352D01*
G01X15906Y1213121D02*
Y1217323D01*
G01D02*
Y1221525D01*
G01X11704Y1217323D02*
X15906D01*
G01D02*
X20108D01*
G01X15906Y1227323D02*
Y1231525D01*
G01X11704Y1227323D02*
X15906D01*
G01D02*
X20108D01*
G01X17716Y1321431D02*
Y1338583D01*
G01D02*
Y1355735D01*
G01Y1338583D02*
X34868D01*
G01X15906Y1472963D02*
Y1477165D01*
G01D02*
Y1481367D01*
G01X11704Y1477165D02*
X15906D01*
G01D02*
X20108D01*
G01X15906Y1487165D02*
Y1491367D01*
G01X11704Y1487165D02*
X15906D01*
G01D02*
X20108D01*
G01X27559Y1811023D02*
Y1828175D01*
G01X10407Y1811023D02*
X27559D01*
G01D02*
X44711D01*
G01X15906Y1906192D02*
Y1910394D01*
G01D02*
Y1914596D01*
G01X11704Y1910394D02*
X15906D01*
G01D02*
X20108D01*
G01X15906Y1920394D02*
Y1924596D01*
G01X11704Y1920394D02*
X15906D01*
G01D02*
X20108D01*
G01X80709Y282677D02*
Y286929D01*
G01D02*
Y291181D01*
G01X76457Y286929D02*
X80709D01*
G01D02*
X84961D01*
G01X80709Y272677D02*
Y276929D01*
G01D02*
Y281181D01*
G01X76457Y276929D02*
X80709D01*
G01D02*
X84961D01*
G01X80709Y262677D02*
Y266929D01*
G01D02*
Y271181D01*
G01X76457Y266929D02*
X80709D01*
G01D02*
X84961D01*
G01X80709Y256929D02*
Y261181D01*
G01X76457Y256929D02*
X80709D01*
G01D02*
X84961D01*
G01X76305Y1747835D02*
X96457D01*
G01X76305Y1823031D02*
X96457D01*
G01X90709Y282677D02*
Y286929D01*
G01D02*
Y291181D01*
G01X86457Y286929D02*
X90709D01*
G01D02*
X94961D01*
G01X90709Y272677D02*
Y276929D01*
G01D02*
Y281181D01*
G01X86457Y276929D02*
X90709D01*
G01D02*
X94961D01*
G01X100709Y282677D02*
Y286929D01*
G01D02*
Y291181D01*
G01X96457Y286929D02*
X100709D01*
G01D02*
X104961D01*
G01X100709Y272677D02*
Y276929D01*
G01D02*
Y281181D01*
G01X96457Y276929D02*
X100709D01*
G01D02*
X104961D01*
G01X110709Y282677D02*
Y286929D01*
G01D02*
Y291181D01*
G01X106457Y286929D02*
X110709D01*
G01D02*
X114961D01*
G01X110709Y272677D02*
Y276929D01*
G01D02*
Y281181D01*
G01X106457Y276929D02*
X110709D01*
G01D02*
X114961D01*
G01X90709Y262677D02*
Y266929D01*
G01D02*
Y271181D01*
G01X86457Y266929D02*
X90709D01*
G01D02*
X94961D01*
G01X90709Y256929D02*
Y261181D01*
G01X86457Y256929D02*
X90709D01*
G01D02*
X94961D01*
G01X100709Y262677D02*
Y266929D01*
G01D02*
Y271181D01*
G01X96457Y266929D02*
X100709D01*
G01D02*
X104961D01*
G01X100709Y256929D02*
Y261181D01*
G01X96457Y256929D02*
X100709D01*
G01D02*
X104961D01*
G01X110709Y262677D02*
Y266929D01*
G01D02*
Y271181D01*
G01X106457Y266929D02*
X110709D01*
G01D02*
X114961D01*
G01X110709Y256929D02*
Y261181D01*
G01X106457Y256929D02*
X110709D01*
G01X96457Y1727683D02*
Y1747835D01*
G01D02*
Y1767987D01*
G01Y1747835D02*
X116609D01*
G01X96457Y1802879D02*
Y1823031D01*
G01D02*
Y1843183D01*
G01Y1823031D02*
X116609D01*
G01X179134Y61588D02*
Y78740D01*
G01D02*
Y95892D01*
G01X161982Y78740D02*
X179134D01*
G01D02*
X196286D01*
G01X149606Y187637D02*
Y191889D01*
G01Y177637D02*
Y181889D01*
G01D02*
Y186141D01*
G01X145354Y181889D02*
X149606D01*
G01D02*
X153858D01*
G01X159606Y187637D02*
Y191889D01*
G01Y177637D02*
Y181889D01*
G01D02*
Y186141D01*
G01X155354Y181889D02*
X159606D01*
G01D02*
X163858D01*
G01X169606Y187637D02*
Y191889D01*
G01Y177637D02*
Y181889D01*
G01D02*
Y186141D01*
G01X165354Y181889D02*
X169606D01*
G01D02*
X173858D01*
G01X179606Y187637D02*
Y191889D01*
G01Y177637D02*
Y181889D01*
G01D02*
Y186141D01*
G01X175354Y181889D02*
X179606D01*
G01D02*
X183858D01*
G01X149606Y167637D02*
Y171889D01*
G01D02*
Y176141D01*
G01X145354Y171889D02*
X149606D01*
G01D02*
X153858D01*
G01X149606Y157637D02*
Y161889D01*
G01D02*
Y166141D01*
G01X145354Y161889D02*
X149606D01*
G01D02*
X153858D01*
G01X159606Y167637D02*
Y171889D01*
G01D02*
Y176141D01*
G01X155354Y171889D02*
X159606D01*
G01D02*
X163858D01*
G01X159606Y157637D02*
Y161889D01*
G01D02*
Y166141D01*
G01X155354Y161889D02*
X159606D01*
G01D02*
X163858D01*
G01X169606Y167637D02*
Y171889D01*
G01D02*
Y176141D01*
G01X165354Y171889D02*
X169606D01*
G01D02*
X173858D01*
G01X169606Y157637D02*
Y161889D01*
G01D02*
Y166141D01*
G01X165354Y161889D02*
X169606D01*
G01D02*
X173858D01*
G01X179606Y167637D02*
Y171889D01*
G01D02*
Y176141D01*
G01X175354Y171889D02*
X179606D01*
G01D02*
X183858D01*
G01X179606Y157637D02*
Y161889D01*
G01D02*
Y166141D01*
G01X175354Y161889D02*
X179606D01*
G01D02*
X183858D01*
G01X149606Y191889D02*
Y196141D01*
G01X145354Y191889D02*
X149606D01*
G01D02*
X153858D01*
G01X159606D02*
Y196141D01*
G01X155354Y191889D02*
X159606D01*
G01D02*
X163858D01*
G01X169606D02*
Y196141D01*
G01X165354Y191889D02*
X169606D01*
G01D02*
X173858D01*
G01X179606D02*
Y196141D01*
G01X175354Y191889D02*
X179606D01*
G01D02*
X183858D01*
G01X149606Y282677D02*
Y286929D01*
G01D02*
Y291181D01*
G01X145354Y286929D02*
X149606D01*
G01D02*
X153858D01*
G01X149606Y272677D02*
Y276929D01*
G01D02*
Y281181D01*
G01X145354Y276929D02*
X149606D01*
G01D02*
X153858D01*
G01X159606Y282677D02*
Y286929D01*
G01D02*
Y291181D01*
G01X155354Y286929D02*
X159606D01*
G01D02*
X163858D01*
G01X159606Y272677D02*
Y276929D01*
G01D02*
Y281181D01*
G01X155354Y276929D02*
X159606D01*
G01D02*
X163858D01*
G01X169606Y282677D02*
Y286929D01*
G01D02*
Y291181D01*
G01X165354Y286929D02*
X169606D01*
G01D02*
X173858D01*
G01X169606Y272677D02*
Y276929D01*
G01D02*
Y281181D01*
G01X165354Y276929D02*
X169606D01*
G01D02*
X173858D01*
G01X179606Y282677D02*
Y286929D01*
G01D02*
Y291181D01*
G01X175354Y286929D02*
X179606D01*
G01D02*
X183858D01*
G01X179606Y272677D02*
Y276929D01*
G01D02*
Y281181D01*
G01X175354Y276929D02*
X179606D01*
G01D02*
X183858D01*
G01X149606Y262677D02*
Y266929D01*
G01D02*
Y271181D01*
G01X145354Y266929D02*
X149606D01*
G01D02*
X153858D01*
G01X149606Y252677D02*
Y256929D01*
G01D02*
Y261181D01*
G01X145354Y256929D02*
X149606D01*
G01D02*
X153858D01*
G01X159606Y262677D02*
Y266929D01*
G01D02*
Y271181D01*
G01X155354Y266929D02*
X159606D01*
G01D02*
X163858D01*
G01X159606Y252677D02*
Y256929D01*
G01D02*
Y261181D01*
G01X155354Y256929D02*
X159606D01*
G01D02*
X163858D01*
G01X169606Y262677D02*
Y266929D01*
G01D02*
Y271181D01*
G01X165354Y266929D02*
X169606D01*
G01D02*
X173858D01*
G01X169606Y252677D02*
Y256929D01*
G01D02*
Y261181D01*
G01X165354Y256929D02*
X169606D01*
G01D02*
X173858D01*
G01X179606Y262677D02*
Y266929D01*
G01D02*
Y271181D01*
G01X175354Y266929D02*
X179606D01*
G01D02*
X183858D01*
G01X179606Y252677D02*
Y256929D01*
G01D02*
Y261181D01*
G01X175354Y256929D02*
X179606D01*
G01D02*
X183858D01*
G01X179133Y553714D02*
Y570866D01*
G01D02*
Y588018D01*
G01X161981Y570866D02*
X179133D01*
G01D02*
X196285D01*
G01X161417Y1727683D02*
Y1747835D01*
G01D02*
Y1767987D01*
G01X141265Y1747835D02*
X161417D01*
G01D02*
X181569D01*
G01X161417Y1802879D02*
Y1823031D01*
G01D02*
Y1843183D01*
G01X141265Y1823031D02*
X161417D01*
G01D02*
X181569D01*
G01X179134Y1872612D02*
Y1889764D01*
G01D02*
Y1906916D01*
G01X161982Y1889764D02*
X179134D01*
G01D02*
X196286D01*
G54D89*
X147500Y1437250D03*
X143625Y1444750D03*
X151375D03*
G54D99*
G01X121640Y963000D02*
Y960960D01*
X123356Y959244D01*
X124618D01*
M02*
